FILE_TYPE = MACRO_DRAWING;
SET COLOR_WIRE YELLOW;
SET COLOR_PROP ORANGE;
SET COLOR_DOT WHITE;
SET COLOR_ARC YELLOW;
SET COLOR_BODY GREEN;
SET COLOR_NOTE PURPLE;
SET PROP_DISPLAY VALUE;
SET PAGE_NUMBER P138;
FORCEADD OFFPAGE..3
(4400 4425);
FORCEPROP 2 LAST $XR1 27 
J 0
(4734 4425);
DISPLAY 0.638298 (4734 4425);
PAINT MONO (4734 4425);
FORCEPROP 2 LAST $XR0 138 
J 0
(4614 4425);
DISPLAY 0.638298 (4614 4425);
PAINT MONO (4614 4425);
FORCEPROP 2 LAST PATH I1
J 0
(4725 4475);
DISPLAY 0.680851 (4725 4475);
DISPLAY INVISIBLE (4725 4475);
FORCEPROP 2 LAST CDS_LIB standard
J 0
(4400 4425);
DISPLAY INVISIBLE (4400 4425);
FORCEPROP 1 LAST OFFPAGE TRUE
J 0
(4725 4300);
DISPLAY 0.872340 (4725 4300);
PAINT GREEN (4725 4300);
DISPLAY INVISIBLE (4725 4300);
FORCEPROP 1 LAST COMMENT_BODY TRUE
J 0
(4350 4325);
DISPLAY 0.872340 (4350 4325);
PAINT PEACH (4350 4325);
DISPLAY INVISIBLE (4350 4325);
FORCEADD Q_RES..1
(2025 5400);
FORCEPROP 1 LAST LOCATION R142
J 0
(1525 5425);
DISPLAY 0.489362 (1525 5425);
PAINT SKYBLUE (1525 5425);
FORCEPROP 0 LAST $SEC 1
J 0
(1925 5475);
DISPLAY 0.680851 (1925 5475);
PAINT MONO (1925 5475);
DISPLAY INVISIBLE (1925 5475);
FORCEPROP 0 LAST CDS_SEC 1
J 0
(1925 5475);
DISPLAY 1.021277 (1925 5475);
DISPLAY INVISIBLE (1925 5475);
FORCEPROP 1 LASTPIN (1925 5400) $PN 1
J 0
(1937 5412);
DISPLAY 0.489362 (1937 5412);
PAINT MONO (1937 5412);
FORCEPROP 1 LASTPIN (2125 5400) $PN 2
J 0
(2087 5412);
DISPLAY 0.489362 (2087 5412);
PAINT MONO (2087 5412);
FORCEPROP 1 LAST MATERIAL EMPTY
J 0
(1725 5425);
DISPLAY 0.489362 (1725 5425);
PAINT RED (1725 5425);
FORCEPROP 1 LAST VALUE 0
J 2
(2125 5425);
DISPLAY 0.489362 (2125 5425);
PAINT SKYBLUE (2125 5425);
FORCEPROP 2 LAST CDS_LIB pure_quanta
J 0
(2025 5400);
DISPLAY INVISIBLE (2025 5400);
FORCEPROP 1 LAST PATH I10
J 0
(1975 5550);
DISPLAY 0.978723 (1975 5550);
PAINT WHITE (1975 5550);
DISPLAY INVISIBLE (1975 5550);
FORCEPROP 1 LAST WATTAGE 1/16W
J 2
(2000 5250);
DISPLAY 0.510638 (2000 5250);
PAINT SKYBLUE (2000 5250);
DISPLAY INVISIBLE (2000 5250);
FORCEPROP 1 LAST TOLERANCE 5%
J 0
(2025 5300);
DISPLAY 0.510638 (2025 5300);
PAINT SKYBLUE (2025 5300);
DISPLAY INVISIBLE (2025 5300);
FORCEPROP 1 LAST PART_NUMBER CS00002JB38
J 0
(1975 5500);
DISPLAY 0.510638 (1975 5500);
PAINT SKYBLUE (1975 5500);
DISPLAY INVISIBLE (1975 5500);
FORCEPROP 1 LAST PACK_TYPE 0402LF
J 0
(2025 5350);
DISPLAY 0.510638 (2025 5350);
PAINT SKYBLUE (2025 5350);
DISPLAY INVISIBLE (2025 5350);
FORCEADD Q_RES..1
(2025 5325);
FORCEPROP 1 LAST LOCATION R143
J 0
(1525 5350);
DISPLAY 0.489362 (1525 5350);
PAINT SKYBLUE (1525 5350);
FORCEPROP 0 LAST $SEC 1
J 0
(1925 5400);
DISPLAY 0.680851 (1925 5400);
PAINT MONO (1925 5400);
DISPLAY INVISIBLE (1925 5400);
FORCEPROP 0 LAST CDS_SEC 1
J 0
(1925 5400);
DISPLAY 1.021277 (1925 5400);
DISPLAY INVISIBLE (1925 5400);
FORCEPROP 1 LASTPIN (1925 5325) $PN 1
J 0
(1937 5337);
DISPLAY 0.489362 (1937 5337);
PAINT MONO (1937 5337);
FORCEPROP 1 LASTPIN (2125 5325) $PN 2
J 0
(2087 5337);
DISPLAY 0.489362 (2087 5337);
PAINT MONO (2087 5337);
FORCEPROP 1 LAST MATERIAL EMPTY
J 0
(1725 5350);
DISPLAY 0.489362 (1725 5350);
PAINT RED (1725 5350);
FORCEPROP 1 LAST VALUE 0
J 2
(2125 5350);
DISPLAY 0.489362 (2125 5350);
PAINT SKYBLUE (2125 5350);
FORCEPROP 2 LAST CDS_LIB pure_quanta
J 0
(2025 5325);
DISPLAY INVISIBLE (2025 5325);
FORCEPROP 1 LAST PATH I11
J 0
(1975 5475);
DISPLAY 0.978723 (1975 5475);
PAINT WHITE (1975 5475);
DISPLAY INVISIBLE (1975 5475);
FORCEPROP 1 LAST WATTAGE 1/16W
J 2
(2000 5175);
DISPLAY 0.510638 (2000 5175);
PAINT SKYBLUE (2000 5175);
DISPLAY INVISIBLE (2000 5175);
FORCEPROP 1 LAST TOLERANCE 5%
J 0
(2025 5225);
DISPLAY 0.510638 (2025 5225);
PAINT SKYBLUE (2025 5225);
DISPLAY INVISIBLE (2025 5225);
FORCEPROP 1 LAST PART_NUMBER CS00002JB38
J 0
(1975 5425);
DISPLAY 0.510638 (1975 5425);
PAINT SKYBLUE (1975 5425);
DISPLAY INVISIBLE (1975 5425);
FORCEPROP 1 LAST PACK_TYPE 0402LF
J 0
(2025 5275);
DISPLAY 0.510638 (2025 5275);
PAINT SKYBLUE (2025 5275);
DISPLAY INVISIBLE (2025 5275);
FORCEADD P1V0..1
(1250 5100);
FORCEPROP 3 LASTPIN (1250 5050) SIG_NAME PVDD18_S5_P0\g
J 0
(1260 5060);
DISPLAY 0.659574 (1260 5060);
PAINT MONO (1260 5060);
DISPLAY INVISIBLE (1260 5060);
FORCEPROP 1 LAST HDL_POWER PVDD18_S5_P0
J 1
(1250 5150);
DISPLAY 0.489362 (1250 5150);
PAINT GREEN (1250 5150);
FORCEPROP 2 LAST CDS_LIB pure_quanta_power
J 0
(1250 5100);
DISPLAY INVISIBLE (1250 5100);
FORCEPROP 1 LAST PATH I12
J 0
(1300 5125);
DISPLAY 0.872340 (1300 5125);
PAINT AQUA (1300 5125);
DISPLAY INVISIBLE (1300 5125);
FORCEADD IML3112Y2B000NCG8..1
(2050 4325);
FORCEPROP 1 LAST LOCATION U213
J 0
(1780 4860);
DISPLAY 0.489362 (1780 4860);
PAINT SKYBLUE (1780 4860);
FORCEPROP 0 LAST $SEC 1
J 0
(1800 5000);
DISPLAY 0.680851 (1800 5000);
PAINT MONO (1800 5000);
DISPLAY INVISIBLE (1800 5000);
FORCEPROP 0 LAST CDS_SEC 1
J 0
(1800 5000);
DISPLAY 1.021277 (1800 5000);
DISPLAY INVISIBLE (1800 5000);
FORCEPROP 0 LASTPIN (1625 4225) $PN 3
J 2
(1615 4235);
DISPLAY 0.489362 (1615 4235);
PAINT MONO (1615 4235);
FORCEPROP 0 LASTPIN (1625 4275) $PN 2
J 2
(1615 4285);
DISPLAY 0.489362 (1615 4285);
PAINT MONO (1615 4285);
FORCEPROP 0 LASTPIN (2475 4375) $PN 4
J 0
(2485 4385);
DISPLAY 0.489362 (2485 4385);
PAINT MONO (2485 4385);
FORCEPROP 0 LASTPIN (2475 4275) $PN 6
J 0
(2485 4285);
DISPLAY 0.489362 (2485 4285);
PAINT MONO (2485 4285);
FORCEPROP 0 LASTPIN (2475 4425) $PN 1
J 0
(2485 4435);
DISPLAY 0.489362 (2485 4435);
PAINT MONO (2485 4435);
FORCEPROP 0 LASTPIN (2475 4225) $PN 8
J 0
(2485 4235);
DISPLAY 0.489362 (2485 4235);
PAINT MONO (2485 4235);
FORCEPROP 0 LASTPIN (2475 4175) $PN 9
J 0
(2485 4185);
DISPLAY 0.489362 (2485 4185);
PAINT MONO (2485 4185);
FORCEPROP 0 LASTPIN (1625 4525) $PN 5
J 2
(1615 4535);
DISPLAY 0.489362 (1615 4535);
PAINT MONO (1615 4535);
FORCEPROP 0 LASTPIN (1625 4475) $PN 7
J 2
(1615 4485);
DISPLAY 0.489362 (1615 4485);
PAINT MONO (1615 4485);
FORCEPROP 2 LAST PART_TYPE SMLF
J 0
(1800 4950);
DISPLAY 1.021277 (1800 4950);
FORCEPROP 1 LAST MATERIAL IC
J 0
(1780 4586);
DISPLAY 0.489362 (1780 4586);
PAINT SKYBLUE (1780 4586);
FORCEPROP 2 LAST VALUE IML3112-Y2B000NCG8
J 0
(1800 4900);
DISPLAY 0.489362 (1800 4900);
PAINT SKYBLUE (1800 4900);
FORCEPROP 1 LAST PART_NUMBER AL003112004
J 0
(1780 4713);
DISPLAY 0.489362 (1780 4713);
PAINT SKYBLUE (1780 4713);
FORCEPROP 2 LAST CDS_LIB pure_quanta
J 0
(2050 4325);
DISPLAY INVISIBLE (2050 4325);
FORCEPROP 1 LAST NEEDS_NO_SIZE TRUE
J 0
(2050 4325);
DISPLAY 0.723404 (2050 4325);
PAINT GREEN (2050 4325);
DISPLAY INVISIBLE (2050 4325);
FORCEPROP 1 LAST CDS_LMAN_SYM_OUTLINE -275,250,275,-250
J 0
(2050 4325);
DISPLAY 0.468085 (2050 4325);
PAINT GREEN (2050 4325);
DISPLAY INVISIBLE (2050 4325);
FORCEPROP 1 LAST PATH I13
J 0
(2050 4325);
DISPLAY 0.723404 (2050 4325);
PAINT GREEN (2050 4325);
DISPLAY INVISIBLE (2050 4325);
FORCEADD Q_RES..1
(800 4925);
FORCEPROP 1 LAST LOCATION R139
J 0
(725 4950);
DISPLAY 0.489362 (725 4950);
PAINT SKYBLUE (725 4950);
FORCEPROP 0 LAST $SEC 1
J 0
(900 4975);
DISPLAY 0.680851 (900 4975);
PAINT MONO (900 4975);
DISPLAY INVISIBLE (900 4975);
FORCEPROP 0 LAST CDS_SEC 1
J 0
(900 4975);
DISPLAY 1.021277 (900 4975);
DISPLAY INVISIBLE (900 4975);
FORCEPROP 1 LASTPIN (700 4925) $PN 1
J 0
(712 4937);
DISPLAY 0.489362 (712 4937);
PAINT MONO (712 4937);
FORCEPROP 1 LASTPIN (900 4925) $PN 2
J 0
(862 4937);
DISPLAY 0.489362 (862 4937);
PAINT MONO (862 4937);
FORCEPROP 1 LAST MATERIAL EMPTY
J 0
(750 4875);
DISPLAY 0.489362 (750 4875);
PAINT RED (750 4875);
FORCEPROP 1 LAST VALUE 0
J 2
(900 4950);
DISPLAY 0.489362 (900 4950);
PAINT SKYBLUE (900 4950);
FORCEPROP 2 LAST CDS_LIB pure_quanta
J 0
(800 4925);
DISPLAY INVISIBLE (800 4925);
FORCEPROP 1 LAST PATH I14
J 0
(750 5075);
DISPLAY 0.978723 (750 5075);
PAINT WHITE (750 5075);
DISPLAY INVISIBLE (750 5075);
FORCEPROP 1 LAST WATTAGE 1/16W
J 2
(775 4775);
DISPLAY 0.510638 (775 4775);
PAINT SKYBLUE (775 4775);
DISPLAY INVISIBLE (775 4775);
FORCEPROP 1 LAST TOLERANCE 5%
J 0
(800 4825);
DISPLAY 0.510638 (800 4825);
PAINT SKYBLUE (800 4825);
DISPLAY INVISIBLE (800 4825);
FORCEPROP 1 LAST PART_NUMBER CS00002JB38
J 0
(750 5025);
DISPLAY 0.510638 (750 5025);
PAINT SKYBLUE (750 5025);
DISPLAY INVISIBLE (750 5025);
FORCEPROP 1 LAST PACK_TYPE 0402LF
J 0
(800 4875);
DISPLAY 0.510638 (800 4875);
PAINT SKYBLUE (800 4875);
DISPLAY INVISIBLE (800 4875);
FORCEADD Q_CAP..1
(1075 4750);
FORCEPROP 1 LAST LOCATION C24
J 0
(975 4875);
DISPLAY 0.489362 (975 4875);
PAINT SKYBLUE (975 4875);
FORCEPROP 0 LAST $SEC 1
J 0
(975 4925);
DISPLAY 0.680851 (975 4925);
PAINT MONO (975 4925);
DISPLAY INVISIBLE (975 4925);
FORCEPROP 0 LAST CDS_SEC 1
J 0
(975 4925);
DISPLAY 1.021277 (975 4925);
DISPLAY INVISIBLE (975 4925);
FORCEPROP 1 LASTPIN (1075 4850) $PN 1
J 0
(1085 4830);
DISPLAY 0.489362 (1085 4830);
PAINT MONO (1085 4830);
FORCEPROP 1 LASTPIN (1075 4650) $PN 2
J 0
(1085 4630);
DISPLAY 0.489362 (1085 4630);
PAINT MONO (1085 4630);
FORCEPROP 1 LAST MATERIAL X6S
J 2
(1025 4700);
DISPLAY 0.489362 (1025 4700);
PAINT SKYBLUE (1025 4700);
FORCEPROP 1 LAST TOLERANCE 20%
J 2
(1025 4750);
DISPLAY 0.489362 (1025 4750);
PAINT SKYBLUE (1025 4750);
FORCEPROP 1 LAST VALUE 10UF
J 2
(1025 4850);
DISPLAY 0.489362 (1025 4850);
PAINT SKYBLUE (1025 4850);
FORCEPROP 1 LAST VOLTAGE 6.3V
J 2
(1025 4800);
DISPLAY 0.489362 (1025 4800);
PAINT SKYBLUE (1025 4800);
FORCEPROP 1 LAST PACK_TYPE C0402
J 2
(1025 4650);
DISPLAY 0.489362 (1025 4650);
PAINT SKYBLUE (1025 4650);
FORCEPROP 2 LAST CDS_LIB pure_quanta
J 0
(1075 4750);
DISPLAY INVISIBLE (1075 4750);
FORCEPROP 1 LAST PATH I15
J 0
(1125 4900);
DISPLAY 0.978723 (1125 4900);
PAINT WHITE (1125 4900);
DISPLAY INVISIBLE (1125 4900);
FORCEPROP 1 LAST PART_NUMBER CH6101MEB01
J 0
(1125 4600);
DISPLAY 0.489362 (1125 4600);
PAINT SKYBLUE (1125 4600);
DISPLAY INVISIBLE (1125 4600);
FORCEADD UNIVERSAL_GND..1
(1075 4550);
FORCEPROP 3 LASTPIN (1075 4600) SIG_NAME GND\g
J 0
(1085 4610);
DISPLAY 0.659574 (1085 4610);
PAINT MONO (1085 4610);
DISPLAY INVISIBLE (1085 4610);
FORCEPROP 2 LAST CDS_LIB pure_quanta_power
J 0
(1075 4550);
DISPLAY INVISIBLE (1075 4550);
FORCEPROP 1 LAST PATH I16
J 0
(1150 4550);
DISPLAY 0.872340 (1150 4550);
PAINT AQUA (1150 4550);
DISPLAY INVISIBLE (1150 4550);
FORCEPROP 1 LAST HDL_POWER GND
J 1
(1100 4475);
DISPLAY 0.872340 (1100 4475);
PAINT GREEN (1100 4475);
DISPLAY INVISIBLE (1100 4475);
FORCEADD Q_CAP..1
(550 4750);
FORCEPROP 1 LAST LOCATION C9
J 0
(450 4875);
DISPLAY 0.489362 (450 4875);
PAINT SKYBLUE (450 4875);
FORCEPROP 0 LAST $SEC 1
J 0
(450 4925);
DISPLAY 0.680851 (450 4925);
PAINT MONO (450 4925);
DISPLAY INVISIBLE (450 4925);
FORCEPROP 0 LAST CDS_SEC 1
J 0
(450 4925);
DISPLAY 1.021277 (450 4925);
DISPLAY INVISIBLE (450 4925);
FORCEPROP 1 LASTPIN (550 4850) $PN 1
J 0
(560 4830);
DISPLAY 0.489362 (560 4830);
PAINT MONO (560 4830);
FORCEPROP 1 LASTPIN (550 4650) $PN 2
J 0
(560 4630);
DISPLAY 0.489362 (560 4630);
PAINT MONO (560 4630);
FORCEPROP 1 LAST MATERIAL X6S
J 2
(500 4700);
DISPLAY 0.489362 (500 4700);
PAINT SKYBLUE (500 4700);
FORCEPROP 1 LAST TOLERANCE 10%
J 2
(500 4750);
DISPLAY 0.489362 (500 4750);
PAINT SKYBLUE (500 4750);
FORCEPROP 1 LAST VALUE 1UF
J 2
(500 4850);
DISPLAY 0.489362 (500 4850);
PAINT SKYBLUE (500 4850);
FORCEPROP 1 LAST VOLTAGE 25V
J 2
(500 4800);
DISPLAY 0.489362 (500 4800);
PAINT SKYBLUE (500 4800);
FORCEPROP 1 LAST PACK_TYPE C0402
J 2
(500 4650);
DISPLAY 0.489362 (500 4650);
PAINT SKYBLUE (500 4650);
FORCEPROP 2 LAST CDS_LIB pure_quanta
J 0
(550 4750);
DISPLAY INVISIBLE (550 4750);
FORCEPROP 1 LAST PATH I17
J 0
(600 4900);
DISPLAY 0.978723 (600 4900);
PAINT WHITE (600 4900);
DISPLAY INVISIBLE (600 4900);
FORCEPROP 1 LAST PART_NUMBER CH5104KEB02
J 0
(600 4600);
DISPLAY 0.489362 (600 4600);
PAINT SKYBLUE (600 4600);
DISPLAY INVISIBLE (600 4600);
FORCEADD UNIVERSAL_GND..1
(550 4550);
FORCEPROP 3 LASTPIN (550 4600) SIG_NAME GND\g
J 0
(560 4610);
DISPLAY 0.659574 (560 4610);
PAINT MONO (560 4610);
DISPLAY INVISIBLE (560 4610);
FORCEPROP 2 LAST CDS_LIB pure_quanta_power
J 0
(550 4550);
DISPLAY INVISIBLE (550 4550);
FORCEPROP 1 LAST PATH I18
J 0
(625 4550);
DISPLAY 0.872340 (625 4550);
PAINT AQUA (625 4550);
DISPLAY INVISIBLE (625 4550);
FORCEPROP 1 LAST HDL_POWER GND
J 1
(575 4475);
DISPLAY 0.872340 (575 4475);
PAINT GREEN (575 4475);
DISPLAY INVISIBLE (575 4475);
FORCEADD OFFPAGE..1
(-450 4225);
FORCEPROP 2 LAST $XR0 137 
J 0
(-732 4225);
DISPLAY 0.638298 (-732 4225);
PAINT MONO (-732 4225);
FORCEPROP 2 LAST PATH I19
J 0
(-725 4275);
DISPLAY 0.680851 (-725 4275);
DISPLAY INVISIBLE (-725 4275);
FORCEPROP 1 LAST COMMENT_BODY TRUE
J 0
(-325 4125);
DISPLAY 0.872340 (-325 4125);
PAINT GREEN (-325 4125);
DISPLAY INVISIBLE (-325 4125);
FORCEPROP 1 LAST OFFPAGE TRUE
J 0
(-125 4100);
DISPLAY 0.872340 (-125 4100);
PAINT GREEN (-125 4100);
DISPLAY INVISIBLE (-125 4100);
FORCEPROP 2 LAST CDS_LIB standard
J 0
(-450 4225);
DISPLAY INVISIBLE (-450 4225);
FORCEADD OFFPAGE..2
(4400 4375);
FORCEPROP 2 LAST $XR1 27 
J 0
(4709 4375);
DISPLAY 0.638298 (4709 4375);
PAINT MONO (4709 4375);
FORCEPROP 2 LAST $XR0 138 
J 0
(4589 4375);
DISPLAY 0.638298 (4589 4375);
PAINT MONO (4589 4375);
FORCEPROP 2 LAST PATH I2
J 0
(4700 4425);
DISPLAY 0.680851 (4700 4425);
DISPLAY INVISIBLE (4700 4425);
FORCEPROP 1 LAST COMMENT_BODY TRUE
J 0
(4355 4280);
DISPLAY 0.872340 (4355 4280);
PAINT GREEN (4355 4280);
DISPLAY INVISIBLE (4355 4280);
FORCEPROP 1 LAST OFFPAGE TRUE
J 0
(4725 4250);
DISPLAY 0.872340 (4725 4250);
PAINT GREEN (4725 4250);
DISPLAY INVISIBLE (4725 4250);
FORCEPROP 2 LAST CDS_LIB standard
J 0
(4400 4375);
DISPLAY INVISIBLE (4400 4375);
FORCEADD OFFPAGE..3
R 2
(-450 4275);
FORCEPROP 2 LAST $XR0 137 
J 0
(-760 4275);
DISPLAY 0.638298 (-760 4275);
PAINT MONO (-760 4275);
FORCEPROP 2 LAST PATH I20
J 0
(-725 4325);
DISPLAY 0.680851 (-725 4325);
DISPLAY INVISIBLE (-725 4325);
FORCEPROP 2 LAST CDS_LIB standard
J 0
(-450 4275);
DISPLAY INVISIBLE (-450 4275);
FORCEPROP 1 LAST OFFPAGE TRUE
J 2
(-775 4150);
DISPLAY 0.872340 (-775 4150);
PAINT GREEN (-775 4150);
DISPLAY INVISIBLE (-775 4150);
FORCEPROP 1 LAST COMMENT_BODY TRUE
J 2
(-400 4175);
DISPLAY 0.872340 (-400 4175);
PAINT GREEN (-400 4175);
DISPLAY INVISIBLE (-400 4175);
FORCEADD OFFPAGE..3
(4425 2300);
FORCEPROP 2 LAST $XR1 54 
J 0
(4759 2300);
DISPLAY 0.638298 (4759 2300);
PAINT MONO (4759 2300);
FORCEPROP 2 LAST $XR0 138 
J 0
(4639 2300);
DISPLAY 0.638298 (4639 2300);
PAINT MONO (4639 2300);
FORCEPROP 2 LAST PATH I21
J 0
(4750 2350);
DISPLAY 0.680851 (4750 2350);
DISPLAY INVISIBLE (4750 2350);
FORCEPROP 1 LAST COMMENT_BODY TRUE
J 0
(4375 2200);
DISPLAY 0.872340 (4375 2200);
PAINT PEACH (4375 2200);
DISPLAY INVISIBLE (4375 2200);
FORCEPROP 1 LAST OFFPAGE TRUE
J 0
(4750 2175);
DISPLAY 0.872340 (4750 2175);
PAINT GREEN (4750 2175);
DISPLAY INVISIBLE (4750 2175);
FORCEPROP 2 LAST CDS_LIB standard
J 0
(4425 2300);
DISPLAY INVISIBLE (4425 2300);
FORCEADD OFFPAGE..2
(4425 2250);
FORCEPROP 2 LAST $XR1 54 
J 0
(4764 2250);
DISPLAY 0.638298 (4764 2250);
PAINT MONO (4764 2250);
FORCEPROP 2 LAST $XR0 138 
J 0
(4644 2250);
DISPLAY 0.638298 (4644 2250);
PAINT MONO (4644 2250);
FORCEPROP 2 LAST CDS_LIB standard
J 0
(4425 2250);
DISPLAY INVISIBLE (4425 2250);
FORCEPROP 2 LAST PATH I22
J 0
(4725 2300);
DISPLAY 0.680851 (4725 2300);
DISPLAY INVISIBLE (4725 2300);
FORCEPROP 1 LAST OFFPAGE TRUE
J 0
(4750 2125);
DISPLAY 0.872340 (4750 2125);
PAINT GREEN (4750 2125);
DISPLAY INVISIBLE (4750 2125);
FORCEPROP 1 LAST COMMENT_BODY TRUE
J 0
(4380 2155);
DISPLAY 0.872340 (4380 2155);
PAINT GREEN (4380 2155);
DISPLAY INVISIBLE (4380 2155);
FORCEADD OFFPAGE..3
(4425 2150);
FORCEPROP 2 LAST $XR1 55 
J 0
(4759 2150);
DISPLAY 0.638298 (4759 2150);
PAINT MONO (4759 2150);
FORCEPROP 2 LAST $XR0 138 
J 0
(4639 2150);
DISPLAY 0.638298 (4639 2150);
PAINT MONO (4639 2150);
FORCEPROP 2 LAST PATH I23
J 0
(4750 2200);
DISPLAY 0.680851 (4750 2200);
DISPLAY INVISIBLE (4750 2200);
FORCEPROP 1 LAST COMMENT_BODY TRUE
J 0
(4375 2050);
DISPLAY 0.872340 (4375 2050);
PAINT PEACH (4375 2050);
DISPLAY INVISIBLE (4375 2050);
FORCEPROP 1 LAST OFFPAGE TRUE
J 0
(4750 2025);
DISPLAY 0.872340 (4750 2025);
PAINT GREEN (4750 2025);
DISPLAY INVISIBLE (4750 2025);
FORCEPROP 2 LAST CDS_LIB standard
J 0
(4425 2150);
DISPLAY INVISIBLE (4425 2150);
FORCEADD OFFPAGE..2
(4425 2100);
FORCEPROP 2 LAST $XR1 138 
J 0
(4734 2100);
DISPLAY 0.638298 (4734 2100);
PAINT MONO (4734 2100);
FORCEPROP 2 LAST $XR0 55 
J 0
(4644 2100);
DISPLAY 0.638298 (4644 2100);
PAINT MONO (4644 2100);
FORCEPROP 2 LAST PATH I24
J 0
(4725 2150);
DISPLAY 0.680851 (4725 2150);
DISPLAY INVISIBLE (4725 2150);
FORCEPROP 1 LAST COMMENT_BODY TRUE
J 0
(4380 2005);
DISPLAY 0.872340 (4380 2005);
PAINT GREEN (4380 2005);
DISPLAY INVISIBLE (4380 2005);
FORCEPROP 1 LAST OFFPAGE TRUE
J 0
(4750 1975);
DISPLAY 0.872340 (4750 1975);
PAINT GREEN (4750 1975);
DISPLAY INVISIBLE (4750 1975);
FORCEPROP 2 LAST CDS_LIB standard
J 0
(4425 2100);
DISPLAY INVISIBLE (4425 2100);
FORCEADD Q_RES..1
(3550 2250);
FORCEPROP 1 LAST LOCATION R1160
J 0
(3350 2250);
DISPLAY 0.489362 (3350 2250);
PAINT SKYBLUE (3350 2250);
FORCEPROP 0 LAST $SEC 1
J 0
(3425 2300);
DISPLAY 0.680851 (3425 2300);
PAINT MONO (3425 2300);
DISPLAY INVISIBLE (3425 2300);
FORCEPROP 0 LAST CDS_SEC 1
J 0
(3425 2300);
DISPLAY 1.021277 (3425 2300);
DISPLAY INVISIBLE (3425 2300);
FORCEPROP 1 LASTPIN (3450 2250) $PN 1
J 0
(3462 2262);
DISPLAY 0.489362 (3462 2262);
PAINT MONO (3462 2262);
FORCEPROP 1 LASTPIN (3650 2250) $PN 2
J 0
(3612 2262);
DISPLAY 0.489362 (3612 2262);
PAINT MONO (3612 2262);
FORCEPROP 1 LAST VALUE 0
J 2
(3750 2250);
DISPLAY 0.489362 (3750 2250);
PAINT SKYBLUE (3750 2250);
FORCEPROP 2 LAST CDS_LIB pure_quanta
J 0
(3550 2250);
DISPLAY INVISIBLE (3550 2250);
FORCEPROP 1 LAST PATH I25
J 0
(3500 2400);
DISPLAY 0.978723 (3500 2400);
PAINT WHITE (3500 2400);
DISPLAY INVISIBLE (3500 2400);
FORCEPROP 1 LAST WATTAGE 1/16W
J 2
(3950 2175);
DISPLAY 0.489362 (3950 2175);
PAINT SKYBLUE (3950 2175);
DISPLAY INVISIBLE (3950 2175);
FORCEPROP 1 LAST MATERIAL CHIP
J 0
(3975 2175);
DISPLAY 0.489362 (3975 2175);
PAINT SKYBLUE (3975 2175);
DISPLAY INVISIBLE (3975 2175);
FORCEPROP 1 LAST TOLERANCE 5%
J 0
(3525 2175);
DISPLAY 0.489362 (3525 2175);
PAINT SKYBLUE (3525 2175);
DISPLAY INVISIBLE (3525 2175);
FORCEPROP 1 LAST PART_NUMBER CS00002JB38
J 0
(3575 2300);
DISPLAY 0.489362 (3575 2300);
PAINT SKYBLUE (3575 2300);
DISPLAY INVISIBLE (3575 2300);
FORCEPROP 1 LAST PACK_TYPE 0402LF
J 0
(3600 2175);
DISPLAY 0.489362 (3600 2175);
PAINT SKYBLUE (3600 2175);
DISPLAY INVISIBLE (3600 2175);
FORCEADD Q_RES..1
(3550 2300);
FORCEPROP 1 LAST LOCATION R1159
J 0
(3350 2300);
DISPLAY 0.489362 (3350 2300);
PAINT SKYBLUE (3350 2300);
FORCEPROP 0 LAST $SEC 1
J 0
(3425 2350);
DISPLAY 0.680851 (3425 2350);
PAINT MONO (3425 2350);
DISPLAY INVISIBLE (3425 2350);
FORCEPROP 0 LAST CDS_SEC 1
J 0
(3425 2350);
DISPLAY 1.021277 (3425 2350);
DISPLAY INVISIBLE (3425 2350);
FORCEPROP 1 LASTPIN (3450 2300) $PN 1
J 0
(3462 2312);
DISPLAY 0.489362 (3462 2312);
PAINT MONO (3462 2312);
FORCEPROP 1 LASTPIN (3650 2300) $PN 2
J 0
(3612 2312);
DISPLAY 0.489362 (3612 2312);
PAINT MONO (3612 2312);
FORCEPROP 1 LAST VALUE 0
J 2
(3750 2300);
DISPLAY 0.489362 (3750 2300);
PAINT SKYBLUE (3750 2300);
FORCEPROP 2 LAST CDS_LIB pure_quanta
J 0
(3550 2300);
DISPLAY INVISIBLE (3550 2300);
FORCEPROP 1 LAST PATH I26
J 0
(3500 2450);
DISPLAY 0.978723 (3500 2450);
PAINT WHITE (3500 2450);
DISPLAY INVISIBLE (3500 2450);
FORCEPROP 1 LAST WATTAGE 1/16W
J 2
(3950 2225);
DISPLAY 0.489362 (3950 2225);
PAINT SKYBLUE (3950 2225);
DISPLAY INVISIBLE (3950 2225);
FORCEPROP 1 LAST MATERIAL CHIP
J 0
(3975 2225);
DISPLAY 0.489362 (3975 2225);
PAINT SKYBLUE (3975 2225);
DISPLAY INVISIBLE (3975 2225);
FORCEPROP 1 LAST TOLERANCE 5%
J 0
(3525 2225);
DISPLAY 0.489362 (3525 2225);
PAINT SKYBLUE (3525 2225);
DISPLAY INVISIBLE (3525 2225);
FORCEPROP 1 LAST PART_NUMBER CS00002JB38
J 0
(3575 2350);
DISPLAY 0.489362 (3575 2350);
PAINT SKYBLUE (3575 2350);
DISPLAY INVISIBLE (3575 2350);
FORCEPROP 1 LAST PACK_TYPE 0402LF
J 0
(3600 2225);
DISPLAY 0.489362 (3600 2225);
PAINT SKYBLUE (3600 2225);
DISPLAY INVISIBLE (3600 2225);
FORCEADD Q_RES..1
(3550 2100);
FORCEPROP 1 LAST LOCATION R1162
J 0
(3350 2100);
DISPLAY 0.489362 (3350 2100);
PAINT SKYBLUE (3350 2100);
FORCEPROP 0 LAST $SEC 1
J 0
(3425 2150);
DISPLAY 0.680851 (3425 2150);
PAINT MONO (3425 2150);
DISPLAY INVISIBLE (3425 2150);
FORCEPROP 0 LAST CDS_SEC 1
J 0
(3425 2150);
DISPLAY 1.021277 (3425 2150);
DISPLAY INVISIBLE (3425 2150);
FORCEPROP 1 LASTPIN (3450 2100) $PN 1
J 0
(3462 2112);
DISPLAY 0.489362 (3462 2112);
PAINT MONO (3462 2112);
FORCEPROP 1 LASTPIN (3650 2100) $PN 2
J 0
(3612 2112);
DISPLAY 0.489362 (3612 2112);
PAINT MONO (3612 2112);
FORCEPROP 1 LAST VALUE 0
J 2
(3750 2100);
DISPLAY 0.489362 (3750 2100);
PAINT SKYBLUE (3750 2100);
FORCEPROP 2 LAST CDS_LIB pure_quanta
J 0
(3550 2100);
DISPLAY INVISIBLE (3550 2100);
FORCEPROP 1 LAST PATH I27
J 0
(3500 2250);
DISPLAY 0.978723 (3500 2250);
PAINT WHITE (3500 2250);
DISPLAY INVISIBLE (3500 2250);
FORCEPROP 1 LAST WATTAGE 1/16W
J 2
(3950 2025);
DISPLAY 0.489362 (3950 2025);
PAINT SKYBLUE (3950 2025);
DISPLAY INVISIBLE (3950 2025);
FORCEPROP 1 LAST MATERIAL CHIP
J 0
(3975 2025);
DISPLAY 0.489362 (3975 2025);
PAINT SKYBLUE (3975 2025);
DISPLAY INVISIBLE (3975 2025);
FORCEPROP 1 LAST TOLERANCE 5%
J 0
(3525 2025);
DISPLAY 0.489362 (3525 2025);
PAINT SKYBLUE (3525 2025);
DISPLAY INVISIBLE (3525 2025);
FORCEPROP 1 LAST PART_NUMBER CS00002JB38
J 0
(3575 2150);
DISPLAY 0.489362 (3575 2150);
PAINT SKYBLUE (3575 2150);
DISPLAY INVISIBLE (3575 2150);
FORCEPROP 1 LAST PACK_TYPE 0402LF
J 0
(3600 2025);
DISPLAY 0.489362 (3600 2025);
PAINT SKYBLUE (3600 2025);
DISPLAY INVISIBLE (3600 2025);
FORCEADD Q_RES..1
(3550 2150);
FORCEPROP 1 LAST LOCATION R1161
J 0
(3350 2150);
DISPLAY 0.489362 (3350 2150);
PAINT SKYBLUE (3350 2150);
FORCEPROP 0 LAST $SEC 1
J 0
(3425 2200);
DISPLAY 0.680851 (3425 2200);
PAINT MONO (3425 2200);
DISPLAY INVISIBLE (3425 2200);
FORCEPROP 0 LAST CDS_SEC 1
J 0
(3425 2200);
DISPLAY 1.021277 (3425 2200);
DISPLAY INVISIBLE (3425 2200);
FORCEPROP 1 LASTPIN (3450 2150) $PN 1
J 0
(3462 2162);
DISPLAY 0.489362 (3462 2162);
PAINT MONO (3462 2162);
FORCEPROP 1 LASTPIN (3650 2150) $PN 2
J 0
(3612 2162);
DISPLAY 0.489362 (3612 2162);
PAINT MONO (3612 2162);
FORCEPROP 1 LAST VALUE 0
J 2
(3750 2150);
DISPLAY 0.489362 (3750 2150);
PAINT SKYBLUE (3750 2150);
FORCEPROP 2 LAST CDS_LIB pure_quanta
J 0
(3550 2150);
DISPLAY INVISIBLE (3550 2150);
FORCEPROP 1 LAST PATH I28
J 0
(3500 2300);
DISPLAY 0.978723 (3500 2300);
PAINT WHITE (3500 2300);
DISPLAY INVISIBLE (3500 2300);
FORCEPROP 1 LAST WATTAGE 1/16W
J 2
(3950 2075);
DISPLAY 0.489362 (3950 2075);
PAINT SKYBLUE (3950 2075);
DISPLAY INVISIBLE (3950 2075);
FORCEPROP 1 LAST MATERIAL CHIP
J 0
(3975 2075);
DISPLAY 0.489362 (3975 2075);
PAINT SKYBLUE (3975 2075);
DISPLAY INVISIBLE (3975 2075);
FORCEPROP 1 LAST TOLERANCE 5%
J 0
(3525 2075);
DISPLAY 0.489362 (3525 2075);
PAINT SKYBLUE (3525 2075);
DISPLAY INVISIBLE (3525 2075);
FORCEPROP 1 LAST PART_NUMBER CS00002JB38
J 0
(3575 2200);
DISPLAY 0.489362 (3575 2200);
PAINT SKYBLUE (3575 2200);
DISPLAY INVISIBLE (3575 2200);
FORCEPROP 1 LAST PACK_TYPE 0402LF
J 0
(3600 2075);
DISPLAY 0.489362 (3600 2075);
PAINT SKYBLUE (3600 2075);
DISPLAY INVISIBLE (3600 2075);
FORCEADD UNIVERSAL_GND..1
(2500 1850);
FORCEPROP 3 LASTPIN (2500 1900) SIG_NAME GND\g
J 0
(2510 1910);
DISPLAY 0.659574 (2510 1910);
PAINT MONO (2510 1910);
DISPLAY INVISIBLE (2510 1910);
FORCEPROP 2 LAST CDS_LIB pure_quanta_power
J 0
(2500 1850);
DISPLAY INVISIBLE (2500 1850);
FORCEPROP 1 LAST PATH I29
J 0
(2575 1850);
DISPLAY 0.872340 (2575 1850);
PAINT AQUA (2575 1850);
DISPLAY INVISIBLE (2575 1850);
FORCEPROP 1 LAST HDL_POWER GND
J 1
(2525 1775);
DISPLAY 0.872340 (2525 1775);
PAINT GREEN (2525 1775);
DISPLAY INVISIBLE (2525 1775);
FORCEADD OFFPAGE..3
(4400 4275);
FORCEPROP 2 LAST $XR1 28 
J 0
(4734 4275);
DISPLAY 0.638298 (4734 4275);
PAINT MONO (4734 4275);
FORCEPROP 2 LAST $XR0 138 
J 0
(4614 4275);
DISPLAY 0.638298 (4614 4275);
PAINT MONO (4614 4275);
FORCEPROP 2 LAST PATH I3
J 0
(4725 4325);
DISPLAY 0.680851 (4725 4325);
DISPLAY INVISIBLE (4725 4325);
FORCEPROP 1 LAST COMMENT_BODY TRUE
J 0
(4350 4175);
DISPLAY 0.872340 (4350 4175);
PAINT PEACH (4350 4175);
DISPLAY INVISIBLE (4350 4175);
FORCEPROP 1 LAST OFFPAGE TRUE
J 0
(4725 4150);
DISPLAY 0.872340 (4725 4150);
PAINT GREEN (4725 4150);
DISPLAY INVISIBLE (4725 4150);
FORCEPROP 2 LAST CDS_LIB standard
J 0
(4400 4275);
DISPLAY INVISIBLE (4400 4275);
FORCEADD Q_RES..1
(2075 3625);
FORCEPROP 1 LAST LOCATION R146
J 0
(1575 3650);
DISPLAY 0.489362 (1575 3650);
PAINT SKYBLUE (1575 3650);
FORCEPROP 0 LAST $SEC 1
J 0
(1975 3700);
DISPLAY 0.680851 (1975 3700);
PAINT MONO (1975 3700);
DISPLAY INVISIBLE (1975 3700);
FORCEPROP 0 LAST CDS_SEC 1
J 0
(1975 3700);
DISPLAY 1.021277 (1975 3700);
DISPLAY INVISIBLE (1975 3700);
FORCEPROP 1 LASTPIN (1975 3625) $PN 1
J 0
(1987 3637);
DISPLAY 0.489362 (1987 3637);
PAINT MONO (1987 3637);
FORCEPROP 1 LASTPIN (2175 3625) $PN 2
J 0
(2137 3637);
DISPLAY 0.489362 (2137 3637);
PAINT MONO (2137 3637);
FORCEPROP 1 LAST MATERIAL EMPTY
J 0
(1775 3650);
DISPLAY 0.489362 (1775 3650);
PAINT RED (1775 3650);
FORCEPROP 1 LAST VALUE 0
J 2
(2175 3650);
DISPLAY 0.489362 (2175 3650);
PAINT SKYBLUE (2175 3650);
FORCEPROP 2 LAST CDS_LIB pure_quanta
J 0
(2075 3625);
DISPLAY INVISIBLE (2075 3625);
FORCEPROP 1 LAST PATH I30
J 0
(2025 3775);
DISPLAY 0.978723 (2025 3775);
PAINT WHITE (2025 3775);
DISPLAY INVISIBLE (2025 3775);
FORCEPROP 1 LAST WATTAGE 1/16W
J 2
(2050 3475);
DISPLAY 0.510638 (2050 3475);
PAINT SKYBLUE (2050 3475);
DISPLAY INVISIBLE (2050 3475);
FORCEPROP 1 LAST TOLERANCE 5%
J 0
(2075 3525);
DISPLAY 0.510638 (2075 3525);
PAINT SKYBLUE (2075 3525);
DISPLAY INVISIBLE (2075 3525);
FORCEPROP 1 LAST PART_NUMBER CS00002JB38
J 0
(2025 3725);
DISPLAY 0.510638 (2025 3725);
PAINT SKYBLUE (2025 3725);
DISPLAY INVISIBLE (2025 3725);
FORCEPROP 1 LAST PACK_TYPE 0402LF
J 0
(2075 3575);
DISPLAY 0.510638 (2075 3575);
PAINT SKYBLUE (2075 3575);
DISPLAY INVISIBLE (2075 3575);
FORCEADD Q_RES..1
(2075 3550);
FORCEPROP 1 LAST LOCATION R147
J 0
(1575 3575);
DISPLAY 0.489362 (1575 3575);
PAINT SKYBLUE (1575 3575);
FORCEPROP 0 LAST $SEC 1
J 0
(1975 3625);
DISPLAY 0.680851 (1975 3625);
PAINT MONO (1975 3625);
DISPLAY INVISIBLE (1975 3625);
FORCEPROP 0 LAST CDS_SEC 1
J 0
(1975 3625);
DISPLAY 1.021277 (1975 3625);
DISPLAY INVISIBLE (1975 3625);
FORCEPROP 1 LASTPIN (1975 3550) $PN 1
J 0
(1987 3562);
DISPLAY 0.489362 (1987 3562);
PAINT MONO (1987 3562);
FORCEPROP 1 LASTPIN (2175 3550) $PN 2
J 0
(2137 3562);
DISPLAY 0.489362 (2137 3562);
PAINT MONO (2137 3562);
FORCEPROP 1 LAST MATERIAL EMPTY
J 0
(1775 3575);
DISPLAY 0.489362 (1775 3575);
PAINT RED (1775 3575);
FORCEPROP 1 LAST VALUE 0
J 2
(2175 3575);
DISPLAY 0.489362 (2175 3575);
PAINT SKYBLUE (2175 3575);
FORCEPROP 2 LAST CDS_LIB pure_quanta
J 0
(2075 3550);
DISPLAY INVISIBLE (2075 3550);
FORCEPROP 1 LAST PATH I31
J 0
(2025 3700);
DISPLAY 0.978723 (2025 3700);
PAINT WHITE (2025 3700);
DISPLAY INVISIBLE (2025 3700);
FORCEPROP 1 LAST WATTAGE 1/16W
J 2
(2050 3400);
DISPLAY 0.510638 (2050 3400);
PAINT SKYBLUE (2050 3400);
DISPLAY INVISIBLE (2050 3400);
FORCEPROP 1 LAST TOLERANCE 5%
J 0
(2075 3450);
DISPLAY 0.510638 (2075 3450);
PAINT SKYBLUE (2075 3450);
DISPLAY INVISIBLE (2075 3450);
FORCEPROP 1 LAST PART_NUMBER CS00002JB38
J 0
(2025 3650);
DISPLAY 0.510638 (2025 3650);
PAINT SKYBLUE (2025 3650);
DISPLAY INVISIBLE (2025 3650);
FORCEPROP 1 LAST PACK_TYPE 0402LF
J 0
(2075 3500);
DISPLAY 0.510638 (2075 3500);
PAINT SKYBLUE (2075 3500);
DISPLAY INVISIBLE (2075 3500);
FORCEADD Q_RES..1
(2025 3200);
FORCEPROP 1 LAST LOCATION R145
J 0
(1525 3225);
DISPLAY 0.489362 (1525 3225);
PAINT SKYBLUE (1525 3225);
FORCEPROP 0 LAST $SEC 1
J 0
(1925 3275);
DISPLAY 0.680851 (1925 3275);
PAINT MONO (1925 3275);
DISPLAY INVISIBLE (1925 3275);
FORCEPROP 0 LAST CDS_SEC 1
J 0
(1925 3275);
DISPLAY 1.021277 (1925 3275);
DISPLAY INVISIBLE (1925 3275);
FORCEPROP 1 LASTPIN (1925 3200) $PN 1
J 0
(1937 3212);
DISPLAY 0.489362 (1937 3212);
PAINT MONO (1937 3212);
FORCEPROP 1 LASTPIN (2125 3200) $PN 2
J 0
(2087 3212);
DISPLAY 0.489362 (2087 3212);
PAINT MONO (2087 3212);
FORCEPROP 1 LAST MATERIAL EMPTY
J 0
(1725 3225);
DISPLAY 0.489362 (1725 3225);
PAINT RED (1725 3225);
FORCEPROP 1 LAST VALUE 0
J 2
(2125 3225);
DISPLAY 0.489362 (2125 3225);
PAINT SKYBLUE (2125 3225);
FORCEPROP 2 LAST CDS_LIB pure_quanta
J 0
(2025 3200);
DISPLAY INVISIBLE (2025 3200);
FORCEPROP 1 LAST PATH I32
J 0
(1975 3350);
DISPLAY 0.978723 (1975 3350);
PAINT WHITE (1975 3350);
DISPLAY INVISIBLE (1975 3350);
FORCEPROP 1 LAST WATTAGE 1/16W
J 2
(2000 3050);
DISPLAY 0.510638 (2000 3050);
PAINT SKYBLUE (2000 3050);
DISPLAY INVISIBLE (2000 3050);
FORCEPROP 1 LAST TOLERANCE 5%
J 0
(2025 3100);
DISPLAY 0.510638 (2025 3100);
PAINT SKYBLUE (2025 3100);
DISPLAY INVISIBLE (2025 3100);
FORCEPROP 1 LAST PART_NUMBER CS00002JB38
J 0
(1975 3300);
DISPLAY 0.510638 (1975 3300);
PAINT SKYBLUE (1975 3300);
DISPLAY INVISIBLE (1975 3300);
FORCEPROP 1 LAST PACK_TYPE 0402LF
J 0
(2025 3150);
DISPLAY 0.510638 (2025 3150);
PAINT SKYBLUE (2025 3150);
DISPLAY INVISIBLE (2025 3150);
FORCEADD Q_RES..1
(2025 3275);
FORCEPROP 1 LAST LOCATION R144
J 0
(1525 3300);
DISPLAY 0.489362 (1525 3300);
PAINT SKYBLUE (1525 3300);
FORCEPROP 0 LAST $SEC 1
J 0
(1925 3350);
DISPLAY 0.680851 (1925 3350);
PAINT MONO (1925 3350);
DISPLAY INVISIBLE (1925 3350);
FORCEPROP 0 LAST CDS_SEC 1
J 0
(1925 3350);
DISPLAY 1.021277 (1925 3350);
DISPLAY INVISIBLE (1925 3350);
FORCEPROP 1 LASTPIN (1925 3275) $PN 1
J 0
(1937 3287);
DISPLAY 0.489362 (1937 3287);
PAINT MONO (1937 3287);
FORCEPROP 1 LASTPIN (2125 3275) $PN 2
J 0
(2087 3287);
DISPLAY 0.489362 (2087 3287);
PAINT MONO (2087 3287);
FORCEPROP 1 LAST MATERIAL EMPTY
J 0
(1725 3300);
DISPLAY 0.489362 (1725 3300);
PAINT RED (1725 3300);
FORCEPROP 1 LAST VALUE 0
J 2
(2125 3300);
DISPLAY 0.489362 (2125 3300);
PAINT SKYBLUE (2125 3300);
FORCEPROP 2 LAST CDS_LIB pure_quanta
J 0
(2025 3275);
DISPLAY INVISIBLE (2025 3275);
FORCEPROP 1 LAST PATH I33
J 0
(1975 3425);
DISPLAY 0.978723 (1975 3425);
PAINT WHITE (1975 3425);
DISPLAY INVISIBLE (1975 3425);
FORCEPROP 1 LAST WATTAGE 1/16W
J 2
(2000 3125);
DISPLAY 0.510638 (2000 3125);
PAINT SKYBLUE (2000 3125);
DISPLAY INVISIBLE (2000 3125);
FORCEPROP 1 LAST TOLERANCE 5%
J 0
(2025 3175);
DISPLAY 0.510638 (2025 3175);
PAINT SKYBLUE (2025 3175);
DISPLAY INVISIBLE (2025 3175);
FORCEPROP 1 LAST PART_NUMBER CS00002JB38
J 0
(1975 3375);
DISPLAY 0.510638 (1975 3375);
PAINT SKYBLUE (1975 3375);
DISPLAY INVISIBLE (1975 3375);
FORCEPROP 1 LAST PACK_TYPE 0402LF
J 0
(2025 3225);
DISPLAY 0.510638 (2025 3225);
PAINT SKYBLUE (2025 3225);
DISPLAY INVISIBLE (2025 3225);
FORCEADD P1V0..1
(1250 2975);
FORCEPROP 3 LASTPIN (1250 2925) SIG_NAME PVDD18_S5_P0\g
J 0
(1260 2935);
DISPLAY 0.659574 (1260 2935);
PAINT MONO (1260 2935);
DISPLAY INVISIBLE (1260 2935);
FORCEPROP 1 LAST HDL_POWER PVDD18_S5_P0
J 1
(1250 3025);
DISPLAY 0.489362 (1250 3025);
PAINT GREEN (1250 3025);
FORCEPROP 2 LAST CDS_LIB pure_quanta_power
J 0
(1250 2975);
DISPLAY INVISIBLE (1250 2975);
FORCEPROP 1 LAST PATH I34
J 0
(1300 3000);
DISPLAY 0.872340 (1300 3000);
PAINT AQUA (1300 3000);
DISPLAY INVISIBLE (1300 3000);
FORCEADD IML3112Y2B000NCG8..1
(2050 2200);
FORCEPROP 1 LAST LOCATION U6
J 0
(1780 2735);
DISPLAY 0.489362 (1780 2735);
PAINT SKYBLUE (1780 2735);
FORCEPROP 0 LAST $SEC 1
J 0
(1800 2875);
DISPLAY 0.680851 (1800 2875);
PAINT MONO (1800 2875);
DISPLAY INVISIBLE (1800 2875);
FORCEPROP 0 LAST CDS_SEC 1
J 0
(1800 2875);
DISPLAY 1.021277 (1800 2875);
DISPLAY INVISIBLE (1800 2875);
FORCEPROP 0 LASTPIN (1625 2100) $PN 3
J 2
(1615 2110);
DISPLAY 0.489362 (1615 2110);
PAINT MONO (1615 2110);
FORCEPROP 0 LASTPIN (1625 2150) $PN 2
J 2
(1615 2160);
DISPLAY 0.489362 (1615 2160);
PAINT MONO (1615 2160);
FORCEPROP 0 LASTPIN (2475 2250) $PN 4
J 0
(2485 2260);
DISPLAY 0.489362 (2485 2260);
PAINT MONO (2485 2260);
FORCEPROP 0 LASTPIN (2475 2150) $PN 6
J 0
(2485 2160);
DISPLAY 0.489362 (2485 2160);
PAINT MONO (2485 2160);
FORCEPROP 0 LASTPIN (2475 2300) $PN 1
J 0
(2485 2310);
DISPLAY 0.489362 (2485 2310);
PAINT MONO (2485 2310);
FORCEPROP 0 LASTPIN (2475 2100) $PN 8
J 0
(2485 2110);
DISPLAY 0.489362 (2485 2110);
PAINT MONO (2485 2110);
FORCEPROP 0 LASTPIN (2475 2050) $PN 9
J 0
(2485 2060);
DISPLAY 0.489362 (2485 2060);
PAINT MONO (2485 2060);
FORCEPROP 0 LASTPIN (1625 2400) $PN 5
J 2
(1615 2410);
DISPLAY 0.489362 (1615 2410);
PAINT MONO (1615 2410);
FORCEPROP 0 LASTPIN (1625 2350) $PN 7
J 2
(1615 2360);
DISPLAY 0.489362 (1615 2360);
PAINT MONO (1615 2360);
FORCEPROP 2 LAST PART_TYPE SMLF
J 0
(1800 2825);
DISPLAY 1.021277 (1800 2825);
FORCEPROP 1 LAST MATERIAL IC
J 0
(1780 2461);
DISPLAY 0.489362 (1780 2461);
PAINT SKYBLUE (1780 2461);
FORCEPROP 1 LAST PART_NUMBER AL003112004
J 0
(1780 2588);
DISPLAY 0.489362 (1780 2588);
PAINT SKYBLUE (1780 2588);
FORCEPROP 2 LAST VALUE IML3112-Y2B000NCG8
J 0
(1800 2775);
DISPLAY 0.489362 (1800 2775);
PAINT SKYBLUE (1800 2775);
FORCEPROP 2 LAST CDS_LIB pure_quanta
J 0
(2050 2200);
DISPLAY INVISIBLE (2050 2200);
FORCEPROP 1 LAST NEEDS_NO_SIZE TRUE
J 0
(2050 2200);
DISPLAY 0.723404 (2050 2200);
PAINT GREEN (2050 2200);
DISPLAY INVISIBLE (2050 2200);
FORCEPROP 1 LAST CDS_LMAN_SYM_OUTLINE -275,250,275,-250
J 0
(2050 2200);
DISPLAY 0.468085 (2050 2200);
PAINT GREEN (2050 2200);
DISPLAY INVISIBLE (2050 2200);
FORCEPROP 1 LAST PATH I35
J 0
(2050 2200);
DISPLAY 0.723404 (2050 2200);
PAINT GREEN (2050 2200);
DISPLAY INVISIBLE (2050 2200);
FORCEADD Q_CAP..1
(1075 2625);
FORCEPROP 1 LAST LOCATION C25
J 0
(1125 2725);
DISPLAY 0.489362 (1125 2725);
PAINT SKYBLUE (1125 2725);
FORCEPROP 0 LAST $SEC 1
J 0
(1125 2775);
DISPLAY 0.680851 (1125 2775);
PAINT MONO (1125 2775);
DISPLAY INVISIBLE (1125 2775);
FORCEPROP 0 LAST CDS_SEC 1
J 0
(1125 2775);
DISPLAY 1.021277 (1125 2775);
DISPLAY INVISIBLE (1125 2775);
FORCEPROP 1 LASTPIN (1075 2725) $PN 1
J 0
(1085 2705);
DISPLAY 0.489362 (1085 2705);
PAINT MONO (1085 2705);
FORCEPROP 1 LASTPIN (1075 2525) $PN 2
J 0
(1085 2505);
DISPLAY 0.489362 (1085 2505);
PAINT MONO (1085 2505);
FORCEPROP 1 LAST MATERIAL X6S
J 2
(1025 2575);
DISPLAY 0.489362 (1025 2575);
PAINT SKYBLUE (1025 2575);
FORCEPROP 1 LAST TOLERANCE 20%
J 2
(1025 2625);
DISPLAY 0.489362 (1025 2625);
PAINT SKYBLUE (1025 2625);
FORCEPROP 1 LAST VALUE 10UF
J 2
(1025 2725);
DISPLAY 0.489362 (1025 2725);
PAINT SKYBLUE (1025 2725);
FORCEPROP 1 LAST VOLTAGE 6.3V
J 2
(1025 2675);
DISPLAY 0.489362 (1025 2675);
PAINT SKYBLUE (1025 2675);
FORCEPROP 1 LAST PACK_TYPE C0402
J 2
(1025 2525);
DISPLAY 0.489362 (1025 2525);
PAINT SKYBLUE (1025 2525);
FORCEPROP 2 LAST CDS_LIB pure_quanta
J 0
(1075 2625);
DISPLAY INVISIBLE (1075 2625);
FORCEPROP 1 LAST PATH I36
J 0
(1125 2775);
DISPLAY 0.978723 (1125 2775);
PAINT WHITE (1125 2775);
DISPLAY INVISIBLE (1125 2775);
FORCEPROP 1 LAST PART_NUMBER CH6101MEB01
J 0
(1125 2475);
DISPLAY 0.489362 (1125 2475);
PAINT SKYBLUE (1125 2475);
DISPLAY INVISIBLE (1125 2475);
FORCEADD UNIVERSAL_GND..1
(1075 2425);
FORCEPROP 3 LASTPIN (1075 2475) SIG_NAME GND\g
J 0
(1085 2485);
DISPLAY 0.659574 (1085 2485);
PAINT MONO (1085 2485);
DISPLAY INVISIBLE (1085 2485);
FORCEPROP 2 LAST CDS_LIB pure_quanta_power
J 0
(1075 2425);
DISPLAY INVISIBLE (1075 2425);
FORCEPROP 1 LAST PATH I37
J 0
(1150 2425);
DISPLAY 0.872340 (1150 2425);
PAINT AQUA (1150 2425);
DISPLAY INVISIBLE (1150 2425);
FORCEPROP 1 LAST HDL_POWER GND
J 1
(1100 2350);
DISPLAY 0.872340 (1100 2350);
PAINT GREEN (1100 2350);
DISPLAY INVISIBLE (1100 2350);
FORCEADD Q_RES..1
(800 2800);
FORCEPROP 1 LAST LOCATION R140
J 0
(750 2850);
DISPLAY 0.489362 (750 2850);
PAINT SKYBLUE (750 2850);
FORCEPROP 0 LAST $SEC 1
J 0
(750 2900);
DISPLAY 0.680851 (750 2900);
PAINT MONO (750 2900);
DISPLAY INVISIBLE (750 2900);
FORCEPROP 0 LAST CDS_SEC 1
J 0
(750 2900);
DISPLAY 1.021277 (750 2900);
DISPLAY INVISIBLE (750 2900);
FORCEPROP 1 LASTPIN (700 2800) $PN 1
J 0
(712 2812);
DISPLAY 0.489362 (712 2812);
PAINT MONO (712 2812);
FORCEPROP 1 LASTPIN (900 2800) $PN 2
J 0
(862 2812);
DISPLAY 0.489362 (862 2812);
PAINT MONO (862 2812);
FORCEPROP 1 LAST MATERIAL EMPTY
J 0
(750 2750);
DISPLAY 0.489362 (750 2750);
PAINT RED (750 2750);
FORCEPROP 1 LAST VALUE 0
J 2
(900 2825);
DISPLAY 0.489362 (900 2825);
PAINT SKYBLUE (900 2825);
FORCEPROP 2 LAST CDS_LIB pure_quanta
J 0
(800 2800);
DISPLAY INVISIBLE (800 2800);
FORCEPROP 1 LAST PATH I38
J 0
(750 2950);
DISPLAY 0.978723 (750 2950);
PAINT WHITE (750 2950);
DISPLAY INVISIBLE (750 2950);
FORCEPROP 1 LAST WATTAGE 1/16W
J 2
(775 2650);
DISPLAY 0.510638 (775 2650);
PAINT SKYBLUE (775 2650);
DISPLAY INVISIBLE (775 2650);
FORCEPROP 1 LAST TOLERANCE 5%
J 0
(800 2700);
DISPLAY 0.510638 (800 2700);
PAINT SKYBLUE (800 2700);
DISPLAY INVISIBLE (800 2700);
FORCEPROP 1 LAST PART_NUMBER CS00002JB38
J 0
(750 2900);
DISPLAY 0.510638 (750 2900);
PAINT SKYBLUE (750 2900);
DISPLAY INVISIBLE (750 2900);
FORCEPROP 1 LAST PACK_TYPE 0402LF
J 0
(800 2750);
DISPLAY 0.510638 (800 2750);
PAINT SKYBLUE (800 2750);
DISPLAY INVISIBLE (800 2750);
FORCEADD UNIVERSAL_GND..1
(550 2425);
FORCEPROP 3 LASTPIN (550 2475) SIG_NAME GND\g
J 0
(560 2485);
DISPLAY 0.659574 (560 2485);
PAINT MONO (560 2485);
DISPLAY INVISIBLE (560 2485);
FORCEPROP 2 LAST CDS_LIB pure_quanta_power
J 0
(550 2425);
DISPLAY INVISIBLE (550 2425);
FORCEPROP 1 LAST PATH I39
J 0
(625 2425);
DISPLAY 0.872340 (625 2425);
PAINT AQUA (625 2425);
DISPLAY INVISIBLE (625 2425);
FORCEPROP 1 LAST HDL_POWER GND
J 1
(575 2350);
DISPLAY 0.872340 (575 2350);
PAINT GREEN (575 2350);
DISPLAY INVISIBLE (575 2350);
FORCEADD OFFPAGE..2
(4400 4225);
FORCEPROP 2 LAST $XR1 138 
J 0
(4679 4225);
DISPLAY 0.638298 (4679 4225);
PAINT MONO (4679 4225);
FORCEPROP 2 LAST $XR0 28 
J 0
(4589 4225);
DISPLAY 0.638298 (4589 4225);
PAINT MONO (4589 4225);
FORCEPROP 2 LAST PATH I4
J 0
(4700 4275);
DISPLAY 0.680851 (4700 4275);
DISPLAY INVISIBLE (4700 4275);
FORCEPROP 1 LAST COMMENT_BODY TRUE
J 0
(4355 4130);
DISPLAY 0.872340 (4355 4130);
PAINT GREEN (4355 4130);
DISPLAY INVISIBLE (4355 4130);
FORCEPROP 1 LAST OFFPAGE TRUE
J 0
(4725 4100);
DISPLAY 0.872340 (4725 4100);
PAINT GREEN (4725 4100);
DISPLAY INVISIBLE (4725 4100);
FORCEPROP 2 LAST CDS_LIB standard
J 0
(4400 4225);
DISPLAY INVISIBLE (4400 4225);
FORCEADD Q_CAP..1
(550 2625);
FORCEPROP 1 LAST LOCATION C22
J 0
(600 2725);
DISPLAY 0.489362 (600 2725);
PAINT SKYBLUE (600 2725);
FORCEPROP 0 LAST $SEC 1
J 0
(600 2775);
DISPLAY 0.680851 (600 2775);
PAINT MONO (600 2775);
DISPLAY INVISIBLE (600 2775);
FORCEPROP 0 LAST CDS_SEC 1
J 0
(600 2775);
DISPLAY 1.021277 (600 2775);
DISPLAY INVISIBLE (600 2775);
FORCEPROP 1 LASTPIN (550 2725) $PN 1
J 0
(560 2705);
DISPLAY 0.489362 (560 2705);
PAINT MONO (560 2705);
FORCEPROP 1 LASTPIN (550 2525) $PN 2
J 0
(560 2505);
DISPLAY 0.489362 (560 2505);
PAINT MONO (560 2505);
FORCEPROP 1 LAST PACK_TYPE C0402
J 2
(500 2525);
DISPLAY 0.489362 (500 2525);
PAINT SKYBLUE (500 2525);
FORCEPROP 1 LAST MATERIAL X6S
J 2
(500 2575);
DISPLAY 0.489362 (500 2575);
PAINT SKYBLUE (500 2575);
FORCEPROP 1 LAST TOLERANCE 10%
J 2
(500 2625);
DISPLAY 0.489362 (500 2625);
PAINT SKYBLUE (500 2625);
FORCEPROP 1 LAST VALUE 1UF
J 2
(500 2725);
DISPLAY 0.489362 (500 2725);
PAINT SKYBLUE (500 2725);
FORCEPROP 1 LAST VOLTAGE 25V
J 2
(500 2675);
DISPLAY 0.489362 (500 2675);
PAINT SKYBLUE (500 2675);
FORCEPROP 2 LAST CDS_LIB pure_quanta
J 0
(550 2625);
DISPLAY INVISIBLE (550 2625);
FORCEPROP 1 LAST PATH I40
J 0
(600 2775);
DISPLAY 0.978723 (600 2775);
PAINT WHITE (600 2775);
DISPLAY INVISIBLE (600 2775);
FORCEPROP 1 LAST PART_NUMBER CH5104KEB02
J 0
(600 2475);
DISPLAY 0.489362 (600 2475);
PAINT SKYBLUE (600 2475);
DISPLAY INVISIBLE (600 2475);
FORCEADD Q_RES..1
(2100 1500);
FORCEPROP 1 LAST LOCATION R148
J 0
(1600 1500);
DISPLAY 0.489362 (1600 1500);
PAINT SKYBLUE (1600 1500);
FORCEPROP 0 LAST $SEC 1
J 0
(2200 1550);
DISPLAY 0.680851 (2200 1550);
PAINT MONO (2200 1550);
DISPLAY INVISIBLE (2200 1550);
FORCEPROP 0 LAST CDS_SEC 1
J 0
(2200 1550);
DISPLAY 1.021277 (2200 1550);
DISPLAY INVISIBLE (2200 1550);
FORCEPROP 1 LASTPIN (2000 1500) $PN 1
J 0
(2012 1512);
DISPLAY 0.489362 (2012 1512);
PAINT MONO (2012 1512);
FORCEPROP 1 LASTPIN (2200 1500) $PN 2
J 0
(2162 1512);
DISPLAY 0.489362 (2162 1512);
PAINT MONO (2162 1512);
FORCEPROP 1 LAST VALUE 0
J 2
(2200 1525);
DISPLAY 0.489362 (2200 1525);
PAINT SKYBLUE (2200 1525);
FORCEPROP 1 LAST MATERIAL EMPTY
J 0
(1800 1525);
DISPLAY 0.489362 (1800 1525);
PAINT RED (1800 1525);
FORCEPROP 2 LAST CDS_LIB pure_quanta
J 0
(2100 1500);
DISPLAY INVISIBLE (2100 1500);
FORCEPROP 1 LAST PATH I41
J 0
(2050 1650);
DISPLAY 0.978723 (2050 1650);
PAINT WHITE (2050 1650);
DISPLAY INVISIBLE (2050 1650);
FORCEPROP 1 LAST WATTAGE 1/16W
J 2
(2075 1350);
DISPLAY 0.510638 (2075 1350);
PAINT SKYBLUE (2075 1350);
DISPLAY INVISIBLE (2075 1350);
FORCEPROP 1 LAST TOLERANCE 5%
J 0
(2100 1400);
DISPLAY 0.510638 (2100 1400);
PAINT SKYBLUE (2100 1400);
DISPLAY INVISIBLE (2100 1400);
FORCEPROP 1 LAST PART_NUMBER CS00002JB38
J 0
(2050 1600);
DISPLAY 0.510638 (2050 1600);
PAINT SKYBLUE (2050 1600);
DISPLAY INVISIBLE (2050 1600);
FORCEPROP 1 LAST PACK_TYPE 0402LF
J 0
(2100 1450);
DISPLAY 0.510638 (2100 1450);
PAINT SKYBLUE (2100 1450);
DISPLAY INVISIBLE (2100 1450);
FORCEADD Q_RES..1
(2100 1425);
FORCEPROP 1 LAST LOCATION R358
J 0
(1600 1425);
DISPLAY 0.489362 (1600 1425);
PAINT SKYBLUE (1600 1425);
FORCEPROP 0 LAST $SEC 1
J 0
(2200 1475);
DISPLAY 0.680851 (2200 1475);
PAINT MONO (2200 1475);
DISPLAY INVISIBLE (2200 1475);
FORCEPROP 0 LAST CDS_SEC 1
J 0
(2200 1475);
DISPLAY 1.021277 (2200 1475);
DISPLAY INVISIBLE (2200 1475);
FORCEPROP 1 LASTPIN (2000 1425) $PN 1
J 0
(2012 1437);
DISPLAY 0.489362 (2012 1437);
PAINT MONO (2012 1437);
FORCEPROP 1 LASTPIN (2200 1425) $PN 2
J 0
(2162 1437);
DISPLAY 0.489362 (2162 1437);
PAINT MONO (2162 1437);
FORCEPROP 1 LAST MATERIAL EMPTY
J 0
(1800 1450);
DISPLAY 0.489362 (1800 1450);
PAINT RED (1800 1450);
FORCEPROP 1 LAST VALUE 0
J 2
(2200 1450);
DISPLAY 0.489362 (2200 1450);
PAINT SKYBLUE (2200 1450);
FORCEPROP 2 LAST CDS_LIB pure_quanta
J 0
(2100 1425);
DISPLAY INVISIBLE (2100 1425);
FORCEPROP 1 LAST PATH I42
J 0
(2050 1575);
DISPLAY 0.978723 (2050 1575);
PAINT WHITE (2050 1575);
DISPLAY INVISIBLE (2050 1575);
FORCEPROP 1 LAST WATTAGE 1/16W
J 2
(2075 1275);
DISPLAY 0.510638 (2075 1275);
PAINT SKYBLUE (2075 1275);
DISPLAY INVISIBLE (2075 1275);
FORCEPROP 1 LAST TOLERANCE 5%
J 0
(2100 1325);
DISPLAY 0.510638 (2100 1325);
PAINT SKYBLUE (2100 1325);
DISPLAY INVISIBLE (2100 1325);
FORCEPROP 1 LAST PART_NUMBER CS00002JB38
J 0
(2050 1525);
DISPLAY 0.510638 (2050 1525);
PAINT SKYBLUE (2050 1525);
DISPLAY INVISIBLE (2050 1525);
FORCEPROP 1 LAST PACK_TYPE 0402LF
J 0
(2100 1375);
DISPLAY 0.510638 (2100 1375);
PAINT SKYBLUE (2100 1375);
DISPLAY INVISIBLE (2100 1375);
FORCEADD OFFPAGE..3
R 2
(-475 2150);
FORCEPROP 2 LAST $XR0 137 
J 0
(-785 2150);
DISPLAY 0.638298 (-785 2150);
PAINT MONO (-785 2150);
FORCEPROP 2 LAST PATH I43
J 0
(-750 2200);
DISPLAY 0.680851 (-750 2200);
DISPLAY INVISIBLE (-750 2200);
FORCEPROP 1 LAST COMMENT_BODY TRUE
J 2
(-425 2050);
DISPLAY 0.872340 (-425 2050);
PAINT GREEN (-425 2050);
DISPLAY INVISIBLE (-425 2050);
FORCEPROP 1 LAST OFFPAGE TRUE
J 2
(-800 2025);
DISPLAY 0.872340 (-800 2025);
PAINT GREEN (-800 2025);
DISPLAY INVISIBLE (-800 2025);
FORCEPROP 2 LAST CDS_LIB standard
J 0
(-475 2150);
DISPLAY INVISIBLE (-475 2150);
FORCEADD OFFPAGE..1
(-475 2100);
FORCEPROP 2 LAST $XR0 137 
J 0
(-787 2100);
DISPLAY 0.638298 (-787 2100);
PAINT MONO (-787 2100);
FORCEPROP 2 LAST PATH I44
J 0
(-750 2150);
DISPLAY 0.680851 (-750 2150);
DISPLAY INVISIBLE (-750 2150);
FORCEPROP 1 LAST COMMENT_BODY TRUE
J 0
(-350 2000);
DISPLAY 0.872340 (-350 2000);
PAINT GREEN (-350 2000);
DISPLAY INVISIBLE (-350 2000);
FORCEPROP 1 LAST OFFPAGE TRUE
J 0
(-150 1975);
DISPLAY 0.872340 (-150 1975);
PAINT GREEN (-150 1975);
DISPLAY INVISIBLE (-150 1975);
FORCEPROP 2 LAST CDS_LIB standard
J 0
(-475 2100);
DISPLAY INVISIBLE (-475 2100);
FORCEADD Q_RES..2
(7250 4050);
FORCEPROP 1 LAST LOCATION R370
J 0
(7295 4175);
DISPLAY 0.489362 (7295 4175);
PAINT SKYBLUE (7295 4175);
FORCEPROP 0 LAST $SEC 1
J 0
(7300 4225);
DISPLAY 0.680851 (7300 4225);
PAINT MONO (7300 4225);
DISPLAY INVISIBLE (7300 4225);
FORCEPROP 0 LAST CDS_SEC 1
J 0
(7300 4225);
DISPLAY 1.021277 (7300 4225);
DISPLAY INVISIBLE (7300 4225);
FORCEPROP 1 LASTPIN (7250 4150) $PN 1
J 0
(7255 4112);
DISPLAY 0.489362 (7255 4112);
PAINT MONO (7255 4112);
FORCEPROP 1 LASTPIN (7250 3950) $PN 2
J 0
(7255 3960);
DISPLAY 0.489362 (7255 3960);
PAINT MONO (7255 3960);
FORCEPROP 1 LAST PACK_TYPE 0402LF
J 0
(7300 3925);
DISPLAY 0.489362 (7300 3925);
PAINT SKYBLUE (7300 3925);
FORCEPROP 1 LAST WATTAGE 1/16W
J 0
(7290 4025);
DISPLAY 0.489362 (7290 4025);
PAINT SKYBLUE (7290 4025);
FORCEPROP 1 LAST MATERIAL CHIP
J 0
(7290 3975);
DISPLAY 0.489362 (7290 3975);
PAINT SKYBLUE (7290 3975);
FORCEPROP 1 LAST TOLERANCE 1%
J 0
(7295 4075);
DISPLAY 0.489362 (7295 4075);
PAINT SKYBLUE (7295 4075);
FORCEPROP 1 LAST VALUE 1K
J 0
(7295 4125);
DISPLAY 0.489362 (7295 4125);
PAINT SKYBLUE (7295 4125);
FORCEPROP 2 LAST CDS_LIB pure_quanta
J 0
(7250 4050);
DISPLAY INVISIBLE (7250 4050);
FORCEPROP 1 LAST PATH I46
J 0
(7300 4225);
DISPLAY 0.978723 (7300 4225);
PAINT WHITE (7300 4225);
DISPLAY INVISIBLE (7300 4225);
FORCEPROP 1 LAST PART_NUMBER TMP_QCS21002FB24
J 0
(7290 3925);
DISPLAY 0.489362 (7290 3925);
PAINT SKYBLUE (7290 3925);
DISPLAY INVISIBLE (7290 3925);
FORCEADD Q_RES..2
(6925 4050);
FORCEPROP 1 LAST LOCATION R367
J 0
(6970 4175);
DISPLAY 0.489362 (6970 4175);
PAINT SKYBLUE (6970 4175);
FORCEPROP 0 LAST $SEC 1
J 0
(6975 4225);
DISPLAY 0.680851 (6975 4225);
PAINT MONO (6975 4225);
DISPLAY INVISIBLE (6975 4225);
FORCEPROP 0 LAST CDS_SEC 1
J 0
(6975 4225);
DISPLAY 1.021277 (6975 4225);
DISPLAY INVISIBLE (6975 4225);
FORCEPROP 1 LASTPIN (6925 4150) $PN 1
J 0
(6930 4112);
DISPLAY 0.489362 (6930 4112);
PAINT MONO (6930 4112);
FORCEPROP 1 LASTPIN (6925 3950) $PN 2
J 0
(6930 3960);
DISPLAY 0.489362 (6930 3960);
PAINT MONO (6930 3960);
FORCEPROP 1 LAST PACK_TYPE 0402LF
J 0
(6975 3925);
DISPLAY 0.489362 (6975 3925);
PAINT SKYBLUE (6975 3925);
FORCEPROP 1 LAST WATTAGE 1/16W
J 0
(6965 4025);
DISPLAY 0.489362 (6965 4025);
PAINT SKYBLUE (6965 4025);
FORCEPROP 1 LAST MATERIAL CHIP
J 0
(6965 3975);
DISPLAY 0.489362 (6965 3975);
PAINT SKYBLUE (6965 3975);
FORCEPROP 1 LAST TOLERANCE 1%
J 0
(6970 4075);
DISPLAY 0.489362 (6970 4075);
PAINT SKYBLUE (6970 4075);
FORCEPROP 1 LAST VALUE 1K
J 0
(6970 4125);
DISPLAY 0.489362 (6970 4125);
PAINT SKYBLUE (6970 4125);
FORCEPROP 2 LAST CDS_LIB pure_quanta
J 0
(6925 4050);
DISPLAY INVISIBLE (6925 4050);
FORCEPROP 1 LAST PATH I48
J 0
(6975 4225);
DISPLAY 0.978723 (6975 4225);
PAINT WHITE (6975 4225);
DISPLAY INVISIBLE (6975 4225);
FORCEPROP 1 LAST PART_NUMBER TMP_QCS21002FB24
J 0
(6965 3925);
DISPLAY 0.489362 (6965 3925);
PAINT SKYBLUE (6965 3925);
DISPLAY INVISIBLE (6965 3925);
FORCEADD Q_RES..1
(3525 4425);
FORCEPROP 1 LAST LOCATION R1155
J 0
(3325 4425);
DISPLAY 0.489362 (3325 4425);
PAINT SKYBLUE (3325 4425);
FORCEPROP 0 LAST $SEC 1
J 0
(3400 4475);
DISPLAY 0.680851 (3400 4475);
PAINT MONO (3400 4475);
DISPLAY INVISIBLE (3400 4475);
FORCEPROP 0 LAST CDS_SEC 1
J 0
(3400 4475);
DISPLAY 1.021277 (3400 4475);
DISPLAY INVISIBLE (3400 4475);
FORCEPROP 1 LASTPIN (3425 4425) $PN 1
J 0
(3437 4437);
DISPLAY 0.489362 (3437 4437);
PAINT MONO (3437 4437);
FORCEPROP 1 LASTPIN (3625 4425) $PN 2
J 0
(3587 4437);
DISPLAY 0.489362 (3587 4437);
PAINT MONO (3587 4437);
FORCEPROP 1 LAST VALUE 0
J 2
(3725 4425);
DISPLAY 0.489362 (3725 4425);
PAINT SKYBLUE (3725 4425);
FORCEPROP 2 LAST CDS_LIB pure_quanta
J 0
(3525 4425);
DISPLAY INVISIBLE (3525 4425);
FORCEPROP 1 LAST PATH I5
J 0
(3475 4575);
DISPLAY 0.978723 (3475 4575);
PAINT WHITE (3475 4575);
DISPLAY INVISIBLE (3475 4575);
FORCEPROP 1 LAST WATTAGE 1/16W
J 2
(3925 4350);
DISPLAY 0.489362 (3925 4350);
PAINT SKYBLUE (3925 4350);
DISPLAY INVISIBLE (3925 4350);
FORCEPROP 1 LAST MATERIAL CHIP
J 0
(3950 4350);
DISPLAY 0.489362 (3950 4350);
PAINT SKYBLUE (3950 4350);
DISPLAY INVISIBLE (3950 4350);
FORCEPROP 1 LAST TOLERANCE 5%
J 0
(3500 4350);
DISPLAY 0.489362 (3500 4350);
PAINT SKYBLUE (3500 4350);
DISPLAY INVISIBLE (3500 4350);
FORCEPROP 1 LAST PART_NUMBER CS00002JB38
J 0
(3550 4475);
DISPLAY 0.489362 (3550 4475);
PAINT SKYBLUE (3550 4475);
DISPLAY INVISIBLE (3550 4475);
FORCEPROP 1 LAST PACK_TYPE 0402LF
J 0
(3575 4350);
DISPLAY 0.489362 (3575 4350);
PAINT SKYBLUE (3575 4350);
DISPLAY INVISIBLE (3575 4350);
FORCEADD Q_RES..2
(6625 4050);
FORCEPROP 1 LAST LOCATION R363
J 0
(6670 4175);
DISPLAY 0.489362 (6670 4175);
PAINT SKYBLUE (6670 4175);
FORCEPROP 0 LAST $SEC 1
J 0
(6675 4225);
DISPLAY 0.680851 (6675 4225);
PAINT MONO (6675 4225);
DISPLAY INVISIBLE (6675 4225);
FORCEPROP 0 LAST CDS_SEC 1
J 0
(6675 4225);
DISPLAY 1.021277 (6675 4225);
DISPLAY INVISIBLE (6675 4225);
FORCEPROP 1 LASTPIN (6625 4150) $PN 1
J 0
(6630 4112);
DISPLAY 0.489362 (6630 4112);
PAINT MONO (6630 4112);
FORCEPROP 1 LASTPIN (6625 3950) $PN 2
J 0
(6630 3960);
DISPLAY 0.489362 (6630 3960);
PAINT MONO (6630 3960);
FORCEPROP 1 LAST WATTAGE 1/16W
J 0
(6665 4025);
DISPLAY 0.489362 (6665 4025);
PAINT SKYBLUE (6665 4025);
FORCEPROP 1 LAST PACK_TYPE 0402LF
J 0
(6675 3925);
DISPLAY 0.489362 (6675 3925);
PAINT SKYBLUE (6675 3925);
FORCEPROP 1 LAST MATERIAL CHIP
J 0
(6665 3975);
DISPLAY 0.489362 (6665 3975);
PAINT SKYBLUE (6665 3975);
FORCEPROP 1 LAST TOLERANCE 1%
J 0
(6670 4075);
DISPLAY 0.489362 (6670 4075);
PAINT SKYBLUE (6670 4075);
FORCEPROP 1 LAST VALUE 1K
J 0
(6670 4125);
DISPLAY 0.489362 (6670 4125);
PAINT SKYBLUE (6670 4125);
FORCEPROP 1 LAST PATH I50
J 0
(6675 4225);
DISPLAY 0.978723 (6675 4225);
PAINT WHITE (6675 4225);
DISPLAY INVISIBLE (6675 4225);
FORCEPROP 2 LAST CDS_LIB pure_quanta
J 0
(6625 4050);
DISPLAY INVISIBLE (6625 4050);
FORCEPROP 1 LAST PART_NUMBER TMP_QCS21002FB24
J 0
(6665 3925);
DISPLAY 0.489362 (6665 3925);
PAINT SKYBLUE (6665 3925);
DISPLAY INVISIBLE (6665 3925);
FORCEADD Q_RES..2
(6300 4050);
FORCEPROP 1 LAST LOCATION R360
J 0
(6345 4175);
DISPLAY 0.489362 (6345 4175);
PAINT SKYBLUE (6345 4175);
FORCEPROP 0 LAST $SEC 1
J 0
(6350 4225);
DISPLAY 0.680851 (6350 4225);
PAINT MONO (6350 4225);
DISPLAY INVISIBLE (6350 4225);
FORCEPROP 0 LAST CDS_SEC 1
J 0
(6350 4225);
DISPLAY 1.021277 (6350 4225);
DISPLAY INVISIBLE (6350 4225);
FORCEPROP 1 LASTPIN (6300 4150) $PN 1
J 0
(6305 4112);
DISPLAY 0.489362 (6305 4112);
PAINT MONO (6305 4112);
FORCEPROP 1 LASTPIN (6300 3950) $PN 2
J 0
(6305 3960);
DISPLAY 0.489362 (6305 3960);
PAINT MONO (6305 3960);
FORCEPROP 1 LAST PACK_TYPE 0402LF
J 0
(6350 3925);
DISPLAY 0.489362 (6350 3925);
PAINT SKYBLUE (6350 3925);
FORCEPROP 1 LAST WATTAGE 1/16W
J 0
(6340 4025);
DISPLAY 0.489362 (6340 4025);
PAINT SKYBLUE (6340 4025);
FORCEPROP 1 LAST MATERIAL CHIP
J 0
(6340 3975);
DISPLAY 0.489362 (6340 3975);
PAINT SKYBLUE (6340 3975);
FORCEPROP 1 LAST TOLERANCE 1%
J 0
(6345 4075);
DISPLAY 0.489362 (6345 4075);
PAINT SKYBLUE (6345 4075);
FORCEPROP 1 LAST VALUE 1K
J 0
(6345 4125);
DISPLAY 0.489362 (6345 4125);
PAINT SKYBLUE (6345 4125);
FORCEPROP 2 LAST CDS_LIB pure_quanta
J 0
(6300 4050);
DISPLAY INVISIBLE (6300 4050);
FORCEPROP 1 LAST PATH I52
J 0
(6350 4225);
DISPLAY 0.978723 (6350 4225);
PAINT WHITE (6350 4225);
DISPLAY INVISIBLE (6350 4225);
FORCEPROP 1 LAST PART_NUMBER TMP_QCS21002FB24
J 0
(6340 3925);
DISPLAY 0.489362 (6340 3925);
PAINT SKYBLUE (6340 3925);
DISPLAY INVISIBLE (6340 3925);
FORCEADD Q_RES..2
(7225 3125);
FORCEPROP 1 LAST LOCATION R369
J 0
(7270 3250);
DISPLAY 0.489362 (7270 3250);
PAINT SKYBLUE (7270 3250);
FORCEPROP 0 LAST $SEC 1
J 0
(7275 3300);
DISPLAY 0.680851 (7275 3300);
PAINT MONO (7275 3300);
DISPLAY INVISIBLE (7275 3300);
FORCEPROP 0 LAST CDS_SEC 1
J 0
(7275 3300);
DISPLAY 1.021277 (7275 3300);
DISPLAY INVISIBLE (7275 3300);
FORCEPROP 1 LASTPIN (7225 3225) $PN 1
J 0
(7230 3187);
DISPLAY 0.489362 (7230 3187);
PAINT MONO (7230 3187);
FORCEPROP 1 LASTPIN (7225 3025) $PN 2
J 0
(7230 3035);
DISPLAY 0.489362 (7230 3035);
PAINT MONO (7230 3035);
FORCEPROP 1 LAST PACK_TYPE 0402LF
J 0
(7275 3000);
DISPLAY 0.489362 (7275 3000);
PAINT SKYBLUE (7275 3000);
FORCEPROP 1 LAST MATERIAL CHIP
J 0
(7265 3050);
DISPLAY 0.489362 (7265 3050);
PAINT SKYBLUE (7265 3050);
FORCEPROP 1 LAST WATTAGE 1/16W
J 0
(7265 3100);
DISPLAY 0.489362 (7265 3100);
PAINT SKYBLUE (7265 3100);
FORCEPROP 1 LAST VALUE 1K
J 0
(7270 3200);
DISPLAY 0.489362 (7270 3200);
PAINT SKYBLUE (7270 3200);
FORCEPROP 1 LAST TOLERANCE 1%
J 0
(7270 3150);
DISPLAY 0.489362 (7270 3150);
PAINT SKYBLUE (7270 3150);
FORCEPROP 1 LAST PATH I54
J 0
(7275 3300);
DISPLAY 0.978723 (7275 3300);
PAINT WHITE (7275 3300);
DISPLAY INVISIBLE (7275 3300);
FORCEPROP 2 LAST CDS_LIB pure_quanta
J 0
(7225 3125);
DISPLAY INVISIBLE (7225 3125);
FORCEPROP 1 LAST PART_NUMBER TMP_QCS21002FB24
J 0
(7265 3000);
DISPLAY 0.489362 (7265 3000);
PAINT SKYBLUE (7265 3000);
DISPLAY INVISIBLE (7265 3000);
FORCEADD Q_RES..2
(6900 3125);
FORCEPROP 1 LAST LOCATION R366
J 0
(6945 3250);
DISPLAY 0.489362 (6945 3250);
PAINT SKYBLUE (6945 3250);
FORCEPROP 0 LAST $SEC 1
J 0
(6950 3300);
DISPLAY 0.680851 (6950 3300);
PAINT MONO (6950 3300);
DISPLAY INVISIBLE (6950 3300);
FORCEPROP 0 LAST CDS_SEC 1
J 0
(6950 3300);
DISPLAY 1.021277 (6950 3300);
DISPLAY INVISIBLE (6950 3300);
FORCEPROP 1 LASTPIN (6900 3225) $PN 1
J 0
(6905 3187);
DISPLAY 0.489362 (6905 3187);
PAINT MONO (6905 3187);
FORCEPROP 1 LASTPIN (6900 3025) $PN 2
J 0
(6905 3035);
DISPLAY 0.489362 (6905 3035);
PAINT MONO (6905 3035);
FORCEPROP 1 LAST MATERIAL CHIP
J 0
(6940 3050);
DISPLAY 0.489362 (6940 3050);
PAINT SKYBLUE (6940 3050);
FORCEPROP 1 LAST PACK_TYPE 0402LF
J 0
(6950 3000);
DISPLAY 0.489362 (6950 3000);
PAINT SKYBLUE (6950 3000);
FORCEPROP 1 LAST WATTAGE 1/16W
J 0
(6940 3100);
DISPLAY 0.489362 (6940 3100);
PAINT SKYBLUE (6940 3100);
FORCEPROP 1 LAST TOLERANCE 1%
J 0
(6945 3150);
DISPLAY 0.489362 (6945 3150);
PAINT SKYBLUE (6945 3150);
FORCEPROP 1 LAST VALUE 1K
J 0
(6945 3200);
DISPLAY 0.489362 (6945 3200);
PAINT SKYBLUE (6945 3200);
FORCEPROP 1 LAST PATH I56
J 0
(6950 3300);
DISPLAY 0.978723 (6950 3300);
PAINT WHITE (6950 3300);
DISPLAY INVISIBLE (6950 3300);
FORCEPROP 2 LAST CDS_LIB pure_quanta
J 0
(6900 3125);
DISPLAY INVISIBLE (6900 3125);
FORCEPROP 1 LAST PART_NUMBER TMP_QCS21002FB24
J 0
(6940 3000);
DISPLAY 0.489362 (6940 3000);
PAINT SKYBLUE (6940 3000);
DISPLAY INVISIBLE (6940 3000);
FORCEADD Q_RES..2
(6600 3125);
FORCEPROP 1 LAST LOCATION R362
J 0
(6645 3250);
DISPLAY 0.489362 (6645 3250);
PAINT SKYBLUE (6645 3250);
FORCEPROP 0 LAST $SEC 1
J 0
(6650 3300);
DISPLAY 0.680851 (6650 3300);
PAINT MONO (6650 3300);
DISPLAY INVISIBLE (6650 3300);
FORCEPROP 0 LAST CDS_SEC 1
J 0
(6650 3300);
DISPLAY 1.021277 (6650 3300);
DISPLAY INVISIBLE (6650 3300);
FORCEPROP 1 LASTPIN (6600 3225) $PN 1
J 0
(6605 3187);
DISPLAY 0.489362 (6605 3187);
PAINT MONO (6605 3187);
FORCEPROP 1 LASTPIN (6600 3025) $PN 2
J 0
(6605 3035);
DISPLAY 0.489362 (6605 3035);
PAINT MONO (6605 3035);
FORCEPROP 1 LAST WATTAGE 1/16W
J 0
(6640 3100);
DISPLAY 0.489362 (6640 3100);
PAINT SKYBLUE (6640 3100);
FORCEPROP 1 LAST PACK_TYPE 0402LF
J 0
(6650 3000);
DISPLAY 0.489362 (6650 3000);
PAINT SKYBLUE (6650 3000);
FORCEPROP 1 LAST MATERIAL CHIP
J 0
(6640 3050);
DISPLAY 0.489362 (6640 3050);
PAINT SKYBLUE (6640 3050);
FORCEPROP 1 LAST TOLERANCE 1%
J 0
(6645 3150);
DISPLAY 0.489362 (6645 3150);
PAINT SKYBLUE (6645 3150);
FORCEPROP 1 LAST VALUE 1K
J 0
(6645 3200);
DISPLAY 0.489362 (6645 3200);
PAINT SKYBLUE (6645 3200);
FORCEPROP 1 LAST PATH I58
J 0
(6650 3300);
DISPLAY 0.978723 (6650 3300);
PAINT WHITE (6650 3300);
DISPLAY INVISIBLE (6650 3300);
FORCEPROP 2 LAST CDS_LIB pure_quanta
J 0
(6600 3125);
DISPLAY INVISIBLE (6600 3125);
FORCEPROP 1 LAST PART_NUMBER TMP_QCS21002FB24
J 0
(6640 3000);
DISPLAY 0.489362 (6640 3000);
PAINT SKYBLUE (6640 3000);
DISPLAY INVISIBLE (6640 3000);
FORCEADD Q_RES..1
(3525 4375);
FORCEPROP 1 LAST LOCATION R1156
J 0
(3325 4375);
DISPLAY 0.489362 (3325 4375);
PAINT SKYBLUE (3325 4375);
FORCEPROP 0 LAST $SEC 1
J 0
(3400 4425);
DISPLAY 0.680851 (3400 4425);
PAINT MONO (3400 4425);
DISPLAY INVISIBLE (3400 4425);
FORCEPROP 0 LAST CDS_SEC 1
J 0
(3400 4425);
DISPLAY 1.021277 (3400 4425);
DISPLAY INVISIBLE (3400 4425);
FORCEPROP 1 LASTPIN (3425 4375) $PN 1
J 0
(3437 4387);
DISPLAY 0.489362 (3437 4387);
PAINT MONO (3437 4387);
FORCEPROP 1 LASTPIN (3625 4375) $PN 2
J 0
(3587 4387);
DISPLAY 0.489362 (3587 4387);
PAINT MONO (3587 4387);
FORCEPROP 1 LAST VALUE 0
J 2
(3725 4375);
DISPLAY 0.489362 (3725 4375);
PAINT SKYBLUE (3725 4375);
FORCEPROP 2 LAST CDS_LIB pure_quanta
J 0
(3525 4375);
DISPLAY INVISIBLE (3525 4375);
FORCEPROP 1 LAST PATH I6
J 0
(3475 4525);
DISPLAY 0.978723 (3475 4525);
PAINT WHITE (3475 4525);
DISPLAY INVISIBLE (3475 4525);
FORCEPROP 1 LAST WATTAGE 1/16W
J 2
(3925 4300);
DISPLAY 0.489362 (3925 4300);
PAINT SKYBLUE (3925 4300);
DISPLAY INVISIBLE (3925 4300);
FORCEPROP 1 LAST MATERIAL CHIP
J 0
(3950 4300);
DISPLAY 0.489362 (3950 4300);
PAINT SKYBLUE (3950 4300);
DISPLAY INVISIBLE (3950 4300);
FORCEPROP 1 LAST TOLERANCE 5%
J 0
(3500 4300);
DISPLAY 0.489362 (3500 4300);
PAINT SKYBLUE (3500 4300);
DISPLAY INVISIBLE (3500 4300);
FORCEPROP 1 LAST PART_NUMBER CS00002JB38
J 0
(3550 4425);
DISPLAY 0.489362 (3550 4425);
PAINT SKYBLUE (3550 4425);
DISPLAY INVISIBLE (3550 4425);
FORCEPROP 1 LAST PACK_TYPE 0402LF
J 0
(3575 4300);
DISPLAY 0.489362 (3575 4300);
PAINT SKYBLUE (3575 4300);
DISPLAY INVISIBLE (3575 4300);
FORCEADD Q_RES..2
(6275 3125);
FORCEPROP 1 LAST LOCATION R359
J 0
(6320 3250);
DISPLAY 0.489362 (6320 3250);
PAINT SKYBLUE (6320 3250);
FORCEPROP 0 LAST $SEC 1
J 0
(6325 3300);
DISPLAY 0.680851 (6325 3300);
PAINT MONO (6325 3300);
DISPLAY INVISIBLE (6325 3300);
FORCEPROP 0 LAST CDS_SEC 1
J 0
(6325 3300);
DISPLAY 1.021277 (6325 3300);
DISPLAY INVISIBLE (6325 3300);
FORCEPROP 1 LASTPIN (6275 3225) $PN 1
J 0
(6280 3187);
DISPLAY 0.489362 (6280 3187);
PAINT MONO (6280 3187);
FORCEPROP 1 LASTPIN (6275 3025) $PN 2
J 0
(6280 3035);
DISPLAY 0.489362 (6280 3035);
PAINT MONO (6280 3035);
FORCEPROP 1 LAST WATTAGE 1/16W
J 0
(6315 3100);
DISPLAY 0.489362 (6315 3100);
PAINT SKYBLUE (6315 3100);
FORCEPROP 1 LAST PACK_TYPE 0402LF
J 0
(6325 3000);
DISPLAY 0.489362 (6325 3000);
PAINT SKYBLUE (6325 3000);
FORCEPROP 1 LAST MATERIAL CHIP
J 0
(6315 3050);
DISPLAY 0.489362 (6315 3050);
PAINT SKYBLUE (6315 3050);
FORCEPROP 1 LAST TOLERANCE 1%
J 0
(6320 3150);
DISPLAY 0.489362 (6320 3150);
PAINT SKYBLUE (6320 3150);
FORCEPROP 1 LAST VALUE 1K
J 0
(6320 3200);
DISPLAY 0.489362 (6320 3200);
PAINT SKYBLUE (6320 3200);
FORCEPROP 2 LAST CDS_LIB pure_quanta
J 0
(6275 3125);
DISPLAY INVISIBLE (6275 3125);
FORCEPROP 1 LAST PATH I60
J 0
(6325 3300);
DISPLAY 0.978723 (6325 3300);
PAINT WHITE (6325 3300);
DISPLAY INVISIBLE (6325 3300);
FORCEPROP 1 LAST PART_NUMBER TMP_QCS21002FB24
J 0
(6315 3000);
DISPLAY 0.489362 (6315 3000);
PAINT SKYBLUE (6315 3000);
DISPLAY INVISIBLE (6315 3000);
FORCEADD VCC_CORE..1
(7250 4400);
FORCEPROP 3 LASTPIN (7250 4350) SIG_NAME PVDD11_S3_P0\g
J 0
(7260 4360);
DISPLAY 0.659574 (7260 4360);
PAINT MONO (7260 4360);
DISPLAY INVISIBLE (7260 4360);
FORCEPROP 1 LAST HDL_POWER PVDD11_S3_P0
J 1
(7250 4450);
DISPLAY 0.489362 (7250 4450);
PAINT GREEN (7250 4450);
FORCEPROP 2 LAST CDS_LIB pure_quanta_power
J 0
(7250 4400);
DISPLAY INVISIBLE (7250 4400);
FORCEPROP 1 LAST PATH I63
J 0
(7300 4425);
DISPLAY 0.872340 (7300 4425);
PAINT AQUA (7300 4425);
DISPLAY INVISIBLE (7300 4425);
FORCEADD VCC_CORE..1
(7225 3475);
FORCEPROP 3 LASTPIN (7225 3425) SIG_NAME PVDD11_S3_P1\g
J 0
(7235 3435);
DISPLAY 0.659574 (7235 3435);
PAINT MONO (7235 3435);
DISPLAY INVISIBLE (7235 3435);
FORCEPROP 1 LAST HDL_POWER PVDD11_S3_P1
J 1
(7225 3525);
DISPLAY 0.489362 (7225 3525);
PAINT GREEN (7225 3525);
FORCEPROP 2 LAST CDS_LIB pure_quanta_power
J 0
(7225 3475);
DISPLAY INVISIBLE (7225 3475);
FORCEPROP 1 LAST PATH I64
J 0
(7275 3500);
DISPLAY 0.872340 (7275 3500);
PAINT AQUA (7275 3500);
DISPLAY INVISIBLE (7275 3500);
FORCEADD OFFPAGE..5
(5500 3775);
FORCEPROP 2 LAST $XR1 27 
J 0
(5155 3775);
DISPLAY 0.638298 (5155 3775);
PAINT MONO (5155 3775);
FORCEPROP 2 LAST $XR0 138 
J 0
(5245 3775);
DISPLAY 0.638298 (5245 3775);
PAINT MONO (5245 3775);
FORCEPROP 2 LAST CDS_LIB standard
J 0
(5500 3775);
DISPLAY INVISIBLE (5500 3775);
FORCEPROP 2 LAST PATH I65
J 0
(5675 3850);
DISPLAY 0.680851 (5675 3850);
DISPLAY INVISIBLE (5675 3850);
FORCEPROP 1 LAST COMMENT_BODY TRUE
J 0
(5600 3700);
DISPLAY 0.872340 (5600 3700);
PAINT GREEN (5600 3700);
DISPLAY INVISIBLE (5600 3700);
FORCEPROP 1 LAST OFFPAGE TRUE
J 0
(5825 3650);
DISPLAY 0.872340 (5825 3650);
PAINT GREEN (5825 3650);
DISPLAY INVISIBLE (5825 3650);
FORCEADD OFFPAGE..5
(5500 3825);
FORCEPROP 2 LAST $XR1 27 
J 0
(5155 3825);
DISPLAY 0.638298 (5155 3825);
PAINT MONO (5155 3825);
FORCEPROP 2 LAST $XR0 138 
J 0
(5245 3825);
DISPLAY 0.638298 (5245 3825);
PAINT MONO (5245 3825);
FORCEPROP 2 LAST CDS_LIB standard
J 0
(5500 3825);
DISPLAY INVISIBLE (5500 3825);
FORCEPROP 2 LAST PATH I66
J 0
(5550 3900);
DISPLAY 0.680851 (5550 3900);
DISPLAY INVISIBLE (5550 3900);
FORCEPROP 1 LAST COMMENT_BODY TRUE
J 0
(5600 3750);
DISPLAY 0.872340 (5600 3750);
PAINT GREEN (5600 3750);
DISPLAY INVISIBLE (5600 3750);
FORCEPROP 1 LAST OFFPAGE TRUE
J 0
(5825 3700);
DISPLAY 0.872340 (5825 3700);
PAINT GREEN (5825 3700);
DISPLAY INVISIBLE (5825 3700);
FORCEADD OFFPAGE..5
(5500 3675);
FORCEPROP 2 LAST $XR1 138 
J 0
(5126 3675);
DISPLAY 0.638298 (5126 3675);
PAINT MONO (5126 3675);
FORCEPROP 2 LAST $XR0 28 
J 0
(5246 3675);
DISPLAY 0.638298 (5246 3675);
PAINT MONO (5246 3675);
FORCEPROP 1 LAST OFFPAGE TRUE
J 0
(5825 3550);
DISPLAY 0.872340 (5825 3550);
PAINT GREEN (5825 3550);
DISPLAY INVISIBLE (5825 3550);
FORCEPROP 1 LAST COMMENT_BODY TRUE
J 0
(5600 3600);
DISPLAY 0.872340 (5600 3600);
PAINT GREEN (5600 3600);
DISPLAY INVISIBLE (5600 3600);
FORCEPROP 2 LAST PATH I67
J 0
(5550 3750);
DISPLAY 0.680851 (5550 3750);
DISPLAY INVISIBLE (5550 3750);
FORCEPROP 2 LAST CDS_LIB standard
J 0
(5500 3675);
DISPLAY INVISIBLE (5500 3675);
FORCEADD OFFPAGE..5
(5500 3725);
FORCEPROP 2 LAST $XR1 28 
J 0
(5155 3725);
DISPLAY 0.638298 (5155 3725);
PAINT MONO (5155 3725);
FORCEPROP 2 LAST $XR0 138 
J 0
(5245 3725);
DISPLAY 0.638298 (5245 3725);
PAINT MONO (5245 3725);
FORCEPROP 1 LAST OFFPAGE TRUE
J 0
(5825 3600);
DISPLAY 0.872340 (5825 3600);
PAINT GREEN (5825 3600);
DISPLAY INVISIBLE (5825 3600);
FORCEPROP 1 LAST COMMENT_BODY TRUE
J 0
(5600 3650);
DISPLAY 0.872340 (5600 3650);
PAINT GREEN (5600 3650);
DISPLAY INVISIBLE (5600 3650);
FORCEPROP 2 LAST PATH I68
J 0
(5550 3800);
DISPLAY 0.680851 (5550 3800);
DISPLAY INVISIBLE (5550 3800);
FORCEPROP 2 LAST CDS_LIB standard
J 0
(5500 3725);
DISPLAY INVISIBLE (5500 3725);
FORCEADD OFFPAGE..5
(5375 2825);
FORCEPROP 2 LAST $XR1 54 
J 0
(5000 2825);
DISPLAY 0.638298 (5000 2825);
PAINT MONO (5000 2825);
FORCEPROP 2 LAST $XR0 138 
J 0
(5090 2825);
DISPLAY 0.638298 (5090 2825);
PAINT MONO (5090 2825);
FORCEPROP 1 LAST OFFPAGE TRUE
J 0
(5700 2700);
DISPLAY 0.872340 (5700 2700);
PAINT GREEN (5700 2700);
DISPLAY INVISIBLE (5700 2700);
FORCEPROP 1 LAST COMMENT_BODY TRUE
J 0
(5475 2750);
DISPLAY 0.872340 (5475 2750);
PAINT GREEN (5475 2750);
DISPLAY INVISIBLE (5475 2750);
FORCEPROP 2 LAST PATH I69
J 0
(5425 2900);
DISPLAY 0.680851 (5425 2900);
DISPLAY INVISIBLE (5425 2900);
FORCEPROP 2 LAST CDS_LIB standard
J 0
(5375 2825);
DISPLAY INVISIBLE (5375 2825);
FORCEADD Q_RES..1
(3525 4275);
FORCEPROP 1 LAST LOCATION R1157
J 0
(3325 4275);
DISPLAY 0.489362 (3325 4275);
PAINT SKYBLUE (3325 4275);
FORCEPROP 0 LAST $SEC 1
J 0
(3400 4325);
DISPLAY 0.680851 (3400 4325);
PAINT MONO (3400 4325);
DISPLAY INVISIBLE (3400 4325);
FORCEPROP 0 LAST CDS_SEC 1
J 0
(3400 4325);
DISPLAY 1.021277 (3400 4325);
DISPLAY INVISIBLE (3400 4325);
FORCEPROP 1 LASTPIN (3425 4275) $PN 1
J 0
(3437 4287);
DISPLAY 0.489362 (3437 4287);
PAINT MONO (3437 4287);
FORCEPROP 1 LASTPIN (3625 4275) $PN 2
J 0
(3587 4287);
DISPLAY 0.489362 (3587 4287);
PAINT MONO (3587 4287);
FORCEPROP 1 LAST VALUE 0
J 2
(3725 4275);
DISPLAY 0.489362 (3725 4275);
PAINT SKYBLUE (3725 4275);
FORCEPROP 2 LAST CDS_LIB pure_quanta
J 0
(3525 4275);
DISPLAY INVISIBLE (3525 4275);
FORCEPROP 1 LAST PATH I7
J 0
(3475 4425);
DISPLAY 0.978723 (3475 4425);
PAINT WHITE (3475 4425);
DISPLAY INVISIBLE (3475 4425);
FORCEPROP 1 LAST WATTAGE 1/16W
J 2
(3925 4200);
DISPLAY 0.489362 (3925 4200);
PAINT SKYBLUE (3925 4200);
DISPLAY INVISIBLE (3925 4200);
FORCEPROP 1 LAST MATERIAL CHIP
J 0
(3950 4200);
DISPLAY 0.489362 (3950 4200);
PAINT SKYBLUE (3950 4200);
DISPLAY INVISIBLE (3950 4200);
FORCEPROP 1 LAST TOLERANCE 5%
J 0
(3500 4200);
DISPLAY 0.489362 (3500 4200);
PAINT SKYBLUE (3500 4200);
DISPLAY INVISIBLE (3500 4200);
FORCEPROP 1 LAST PART_NUMBER CS00002JB38
J 0
(3550 4325);
DISPLAY 0.489362 (3550 4325);
PAINT SKYBLUE (3550 4325);
DISPLAY INVISIBLE (3550 4325);
FORCEPROP 1 LAST PACK_TYPE 0402LF
J 0
(3575 4200);
DISPLAY 0.489362 (3575 4200);
PAINT SKYBLUE (3575 4200);
DISPLAY INVISIBLE (3575 4200);
FORCEADD OFFPAGE..5
(5375 2875);
FORCEPROP 2 LAST $XR1 54 
J 0
(5000 2875);
DISPLAY 0.638298 (5000 2875);
PAINT MONO (5000 2875);
FORCEPROP 2 LAST $XR0 138 
J 0
(5090 2875);
DISPLAY 0.638298 (5090 2875);
PAINT MONO (5090 2875);
FORCEPROP 1 LAST OFFPAGE TRUE
J 0
(5700 2750);
DISPLAY 0.872340 (5700 2750);
PAINT GREEN (5700 2750);
DISPLAY INVISIBLE (5700 2750);
FORCEPROP 1 LAST COMMENT_BODY TRUE
J 0
(5475 2800);
DISPLAY 0.872340 (5475 2800);
PAINT GREEN (5475 2800);
DISPLAY INVISIBLE (5475 2800);
FORCEPROP 2 LAST PATH I70
J 0
(5425 2950);
DISPLAY 0.680851 (5425 2950);
DISPLAY INVISIBLE (5425 2950);
FORCEPROP 2 LAST CDS_LIB standard
J 0
(5375 2875);
DISPLAY INVISIBLE (5375 2875);
FORCEADD OFFPAGE..5
(5375 2725);
FORCEPROP 2 LAST $XR1 138 
J 0
(5001 2725);
DISPLAY 0.638298 (5001 2725);
PAINT MONO (5001 2725);
FORCEPROP 2 LAST $XR0 55 
J 0
(5121 2725);
DISPLAY 0.638298 (5121 2725);
PAINT MONO (5121 2725);
FORCEPROP 1 LAST OFFPAGE TRUE
J 0
(5700 2600);
DISPLAY 0.872340 (5700 2600);
PAINT GREEN (5700 2600);
DISPLAY INVISIBLE (5700 2600);
FORCEPROP 1 LAST COMMENT_BODY TRUE
J 0
(5475 2650);
DISPLAY 0.872340 (5475 2650);
PAINT GREEN (5475 2650);
DISPLAY INVISIBLE (5475 2650);
FORCEPROP 2 LAST PATH I71
J 0
(5425 2800);
DISPLAY 0.680851 (5425 2800);
DISPLAY INVISIBLE (5425 2800);
FORCEPROP 2 LAST CDS_LIB standard
J 0
(5375 2725);
DISPLAY INVISIBLE (5375 2725);
FORCEADD OFFPAGE..5
(5375 2775);
FORCEPROP 2 LAST $XR1 55 
J 0
(5000 2775);
DISPLAY 0.638298 (5000 2775);
PAINT MONO (5000 2775);
FORCEPROP 2 LAST $XR0 138 
J 0
(5090 2775);
DISPLAY 0.638298 (5090 2775);
PAINT MONO (5090 2775);
FORCEPROP 1 LAST OFFPAGE TRUE
J 0
(5700 2650);
DISPLAY 0.872340 (5700 2650);
PAINT GREEN (5700 2650);
DISPLAY INVISIBLE (5700 2650);
FORCEPROP 1 LAST COMMENT_BODY TRUE
J 0
(5475 2700);
DISPLAY 0.872340 (5475 2700);
PAINT GREEN (5475 2700);
DISPLAY INVISIBLE (5475 2700);
FORCEPROP 2 LAST PATH I72
J 0
(5425 2850);
DISPLAY 0.680851 (5425 2850);
DISPLAY INVISIBLE (5425 2850);
FORCEPROP 2 LAST CDS_LIB standard
J 0
(5375 2775);
DISPLAY INVISIBLE (5375 2775);
FORCEADD Q_RES..2
(3375 4000);
FORCEPROP 1 LAST LOCATION R5004
J 0
(3420 4125);
DISPLAY 0.489362 (3420 4125);
PAINT SKYBLUE (3420 4125);
FORCEPROP 0 LAST $SEC 1
J 0
(3425 4150);
DISPLAY 0.680851 (3425 4150);
PAINT MONO (3425 4150);
DISPLAY INVISIBLE (3425 4150);
FORCEPROP 0 LAST CDS_SEC 1
J 0
(3425 4150);
DISPLAY 0.680851 (3425 4150);
DISPLAY INVISIBLE (3425 4150);
FORCEPROP 1 LASTPIN (3375 4100) $PN 1
J 0
(3380 4062);
DISPLAY 0.787234 (3380 4062);
PAINT MONO (3380 4062);
FORCEPROP 1 LASTPIN (3375 3900) $PN 2
J 0
(3380 3910);
DISPLAY 0.787234 (3380 3910);
PAINT MONO (3380 3910);
FORCEPROP 1 LAST PACK_TYPE 0402LF
J 0
(3425 3875);
DISPLAY 0.489362 (3425 3875);
PAINT SKYBLUE (3425 3875);
FORCEPROP 1 LAST MATERIAL CHIP
J 0
(3415 3925);
DISPLAY 0.489362 (3415 3925);
PAINT SKYBLUE (3415 3925);
FORCEPROP 1 LAST TOLERANCE 1%
J 0
(3420 4025);
DISPLAY 0.489362 (3420 4025);
PAINT SKYBLUE (3420 4025);
FORCEPROP 1 LAST WATTAGE 1/16W
J 0
(3415 3975);
DISPLAY 0.489362 (3415 3975);
PAINT SKYBLUE (3415 3975);
FORCEPROP 1 LAST VALUE 10K
J 0
(3420 4075);
DISPLAY 0.489362 (3420 4075);
PAINT SKYBLUE (3420 4075);
FORCEPROP 1 LAST PATH I73
J 0
(3425 4175);
DISPLAY 0.978723 (3425 4175);
PAINT WHITE (3425 4175);
DISPLAY INVISIBLE (3425 4175);
FORCEPROP 2 LAST CDS_LIB pure_quanta
J 0
(3375 4000);
DISPLAY INVISIBLE (3375 4000);
FORCEPROP 1 LAST PART_NUMBER CS31002FB08
J 0
(3415 3875);
DISPLAY 0.489362 (3415 3875);
PAINT SKYBLUE (3415 3875);
DISPLAY INVISIBLE (3415 3875);
FORCEADD UNIVERSAL_GND..1
(3375 3750);
FORCEPROP 3 LASTPIN (3375 3800) SIG_NAME GND\g
J 0
(3385 3810);
DISPLAY 0.659574 (3385 3810);
PAINT MONO (3385 3810);
DISPLAY INVISIBLE (3385 3810);
FORCEPROP 1 LAST HDL_POWER GND
J 1
(3400 3675);
DISPLAY 0.872340 (3400 3675);
PAINT GREEN (3400 3675);
DISPLAY INVISIBLE (3400 3675);
FORCEPROP 1 LAST PATH I74
J 0
(3450 3750);
DISPLAY 0.872340 (3450 3750);
PAINT AQUA (3450 3750);
DISPLAY INVISIBLE (3450 3750);
FORCEPROP 2 LAST CDS_LIB pure_quanta_power
J 0
(3375 3750);
DISPLAY INVISIBLE (3375 3750);
FORCEADD Q_RES..2
(3375 1875);
FORCEPROP 1 LAST LOCATION R5005
J 0
(3420 2000);
DISPLAY 0.489362 (3420 2000);
PAINT SKYBLUE (3420 2000);
FORCEPROP 0 LAST $SEC 1
J 0
(3425 2025);
DISPLAY 0.680851 (3425 2025);
PAINT MONO (3425 2025);
DISPLAY INVISIBLE (3425 2025);
FORCEPROP 0 LAST CDS_SEC 1
J 0
(3425 2025);
DISPLAY 0.680851 (3425 2025);
DISPLAY INVISIBLE (3425 2025);
FORCEPROP 1 LASTPIN (3375 1975) $PN 1
J 0
(3380 1937);
DISPLAY 0.787234 (3380 1937);
PAINT MONO (3380 1937);
FORCEPROP 1 LASTPIN (3375 1775) $PN 2
J 0
(3380 1785);
DISPLAY 0.787234 (3380 1785);
PAINT MONO (3380 1785);
FORCEPROP 1 LAST TOLERANCE 1%
J 0
(3420 1900);
DISPLAY 0.489362 (3420 1900);
PAINT SKYBLUE (3420 1900);
FORCEPROP 1 LAST PACK_TYPE 0402LF
J 0
(3425 1750);
DISPLAY 0.489362 (3425 1750);
PAINT SKYBLUE (3425 1750);
FORCEPROP 1 LAST VALUE 10K
J 0
(3420 1950);
DISPLAY 0.489362 (3420 1950);
PAINT SKYBLUE (3420 1950);
FORCEPROP 1 LAST MATERIAL CHIP
J 0
(3415 1800);
DISPLAY 0.489362 (3415 1800);
PAINT SKYBLUE (3415 1800);
FORCEPROP 1 LAST WATTAGE 1/16W
J 0
(3415 1850);
DISPLAY 0.489362 (3415 1850);
PAINT SKYBLUE (3415 1850);
FORCEPROP 1 LAST PATH I75
J 0
(3425 2050);
DISPLAY 0.978723 (3425 2050);
PAINT WHITE (3425 2050);
DISPLAY INVISIBLE (3425 2050);
FORCEPROP 2 LAST CDS_LIB pure_quanta
J 0
(3375 1875);
DISPLAY INVISIBLE (3375 1875);
FORCEPROP 1 LAST PART_NUMBER CS31002FB08
J 0
(3415 1750);
DISPLAY 0.489362 (3415 1750);
PAINT SKYBLUE (3415 1750);
DISPLAY INVISIBLE (3415 1750);
FORCEADD UNIVERSAL_GND..1
(3375 1625);
FORCEPROP 3 LASTPIN (3375 1675) SIG_NAME GND\g
J 0
(3385 1685);
DISPLAY 0.659574 (3385 1685);
PAINT MONO (3385 1685);
DISPLAY INVISIBLE (3385 1685);
FORCEPROP 1 LAST HDL_POWER GND
J 1
(3400 1550);
DISPLAY 0.872340 (3400 1550);
PAINT GREEN (3400 1550);
DISPLAY INVISIBLE (3400 1550);
FORCEPROP 1 LAST PATH I76
J 0
(3450 1625);
DISPLAY 0.872340 (3450 1625);
PAINT AQUA (3450 1625);
DISPLAY INVISIBLE (3450 1625);
FORCEPROP 2 LAST CDS_LIB pure_quanta_power
J 0
(3375 1625);
DISPLAY INVISIBLE (3375 1625);
FORCEADD Q_RES..1
(3525 4225);
FORCEPROP 1 LAST LOCATION R1158
J 0
(3325 4225);
DISPLAY 0.489362 (3325 4225);
PAINT SKYBLUE (3325 4225);
FORCEPROP 0 LAST $SEC 1
J 0
(3400 4275);
DISPLAY 0.680851 (3400 4275);
PAINT MONO (3400 4275);
DISPLAY INVISIBLE (3400 4275);
FORCEPROP 0 LAST CDS_SEC 1
J 0
(3400 4275);
DISPLAY 1.021277 (3400 4275);
DISPLAY INVISIBLE (3400 4275);
FORCEPROP 1 LASTPIN (3425 4225) $PN 1
J 0
(3437 4237);
DISPLAY 0.489362 (3437 4237);
PAINT MONO (3437 4237);
FORCEPROP 1 LASTPIN (3625 4225) $PN 2
J 0
(3587 4237);
DISPLAY 0.489362 (3587 4237);
PAINT MONO (3587 4237);
FORCEPROP 1 LAST VALUE 0
J 2
(3725 4225);
DISPLAY 0.489362 (3725 4225);
PAINT SKYBLUE (3725 4225);
FORCEPROP 2 LAST CDS_LIB pure_quanta
J 0
(3525 4225);
DISPLAY INVISIBLE (3525 4225);
FORCEPROP 1 LAST PATH I8
J 0
(3475 4375);
DISPLAY 0.978723 (3475 4375);
PAINT WHITE (3475 4375);
DISPLAY INVISIBLE (3475 4375);
FORCEPROP 1 LAST WATTAGE 1/16W
J 2
(3925 4150);
DISPLAY 0.489362 (3925 4150);
PAINT SKYBLUE (3925 4150);
DISPLAY INVISIBLE (3925 4150);
FORCEPROP 1 LAST MATERIAL CHIP
J 0
(3950 4150);
DISPLAY 0.489362 (3950 4150);
PAINT SKYBLUE (3950 4150);
DISPLAY INVISIBLE (3950 4150);
FORCEPROP 1 LAST TOLERANCE 5%
J 0
(3500 4150);
DISPLAY 0.489362 (3500 4150);
PAINT SKYBLUE (3500 4150);
DISPLAY INVISIBLE (3500 4150);
FORCEPROP 1 LAST PART_NUMBER CS00002JB38
J 0
(3550 4275);
DISPLAY 0.489362 (3550 4275);
PAINT SKYBLUE (3550 4275);
DISPLAY INVISIBLE (3550 4275);
FORCEPROP 1 LAST PACK_TYPE 0402LF
J 0
(3575 4150);
DISPLAY 0.489362 (3575 4150);
PAINT SKYBLUE (3575 4150);
DISPLAY INVISIBLE (3575 4150);
FORCEADD UNIVERSAL_GND..1
(2500 3975);
FORCEPROP 3 LASTPIN (2500 4025) SIG_NAME GND\g
J 0
(2510 4035);
DISPLAY 0.659574 (2510 4035);
PAINT MONO (2510 4035);
DISPLAY INVISIBLE (2510 4035);
FORCEPROP 2 LAST CDS_LIB pure_quanta_power
J 0
(2500 3975);
DISPLAY INVISIBLE (2500 3975);
FORCEPROP 1 LAST PATH I9
J 0
(2575 3975);
DISPLAY 0.872340 (2575 3975);
PAINT AQUA (2575 3975);
DISPLAY INVISIBLE (2575 3975);
FORCEPROP 1 LAST HDL_POWER GND
J 1
(2525 3900);
DISPLAY 0.872340 (2525 3900);
PAINT GREEN (2525 3900);
DISPLAY INVISIBLE (2525 3900);
FORCEADD DNS..1
(750 4900);
PAINT RED (750 4900);
FORCEPROP 2 LAST CDS_LIB mstr_misc
J 0
(750 4900);
DISPLAY INVISIBLE (750 4900);
FORCEPROP 1 LAST COMMENT_BODY TRUE
R 1
J 0
(825 4675);
DISPLAY 0.872340 (825 4675);
PAINT GREEN (825 4675);
DISPLAY INVISIBLE (825 4675);
FORCEADD DNS..1
(750 2775);
PAINT RED (750 2775);
FORCEPROP 2 LAST CDS_LIB mstr_misc
J 0
(750 2775);
DISPLAY INVISIBLE (750 2775);
FORCEPROP 1 LAST COMMENT_BODY TRUE
R 1
J 0
(825 2550);
DISPLAY 0.872340 (825 2550);
PAINT GREEN (825 2550);
DISPLAY INVISIBLE (825 2550);
FORCEADD DNS..1
(2150 3600);
PAINT RED (2150 3600);
FORCEPROP 2 LAST CDS_LIB mstr_misc
J 0
(2150 3600);
DISPLAY INVISIBLE (2150 3600);
FORCEPROP 1 LAST COMMENT_BODY TRUE
R 1
J 0
(2225 3375);
DISPLAY 0.872340 (2225 3375);
PAINT GREEN (2225 3375);
DISPLAY INVISIBLE (2225 3375);
FORCEADD DNS..1
(2175 1475);
PAINT RED (2175 1475);
FORCEPROP 2 LAST CDS_LIB mstr_misc
J 0
(2175 1475);
DISPLAY INVISIBLE (2175 1475);
FORCEPROP 1 LAST COMMENT_BODY TRUE
R 1
J 0
(2250 1250);
DISPLAY 0.872340 (2250 1250);
PAINT GREEN (2250 1250);
DISPLAY INVISIBLE (2250 1250);
FORCEADD QUANTA_TITLE_BLOCK_C..1
(7925 -50);
FORCEPROP 0 LAST CDS_CON_LAST_MODIFIED Fri Mar 11 14:53:14 2022
J 0
(6040 -35);
DISPLAY INVISIBLE (6040 -35);
FORCEPROP 1 LAST CUSTOM_TXT_CDS <CON_LAST_MODIFIED>
J 0
(6040 -35);
DISPLAY 0.978723 (6040 -35);
FORCEPROP 2 LAST CUSTOM_TXT_CDS <XR_PAGE_TITLE>
J 0
(35 5200);
DISPLAY 0.638298 (35 5200);
PAINT PINK (35 5200);
DISPLAY INVISIBLE (35 5200);
FORCEPROP 1 LAST CUSTOM_TXT_CDS <NAME_2>
J 0
(4750 0);
FORCEPROP 1 LAST CUSTOM_TXT_CDS <NAME_1>
J 0
(4750 125);
FORCEPROP 1 LAST CUSTOM_TXT_CDS <Q_NUMBER>
J 0
(6522 53);
DISPLAY 1.212766 (6522 53);
FORCEPROP 1 LAST CUSTOM_TXT_CDS <Q_PROJ>
J 0
(5543 52);
DISPLAY 1.212766 (5543 52);
FORCEPROP 1 LAST CUSTOM_TXT_CDS <Q_REV>
J 0
(7741 53);
DISPLAY 1.212766 (7741 53);
FORCEPROP 1 LAST CUSTOM_TXT_CDS <CON_PAGE_NUM> OF <CON_TOTAL_PAGES>
J 0
(7479 -32);
DISPLAY 0.978723 (7479 -32);
FORCEPROP 1 LAST Q_TITLE I2C MUX - APML(2/2)
J 0
(-1375 25);
DISPLAY 2.446809 (-1375 25);
PAINT GREEN (-1375 25);
FORCEPROP 1 LAST Q_DEPT BU9
J 1
(4162 -1);
DISPLAY 1.957447 (4162 -1);
PAINT GREEN (4162 -1);
FORCEPROP 2 LAST PAGE_BORDER TRUE
J 0
(35 5200);
DISPLAY 0.638298 (35 5200);
PAINT PINK (35 5200);
DISPLAY INVISIBLE (35 5200);
FORCEPROP 1 LAST CDS_LMAN_SYM_OUTLINE -9475,6775,100,-125
J 0
(7925 -50);
DISPLAY 0.468085 (7925 -50);
PAINT GREEN (7925 -50);
DISPLAY INVISIBLE (7925 -50);
FORCEPROP 2 LAST CDS_LIB pure_quanta
J 0
(7925 -50);
DISPLAY INVISIBLE (7925 -50);
FORCEPROP 1 LAST COMMENT_BODY TRUE
J 0
(7937 -63);
DISPLAY 0.978723 (7937 -63);
PAINT GREEN (7937 -63);
DISPLAY INVISIBLE (7937 -63);
FORCEPROP 2 LAST CDS_XR_PAGE_TITLE CR-138 : @T6G_MB_LIB.T6G(SCH_1):PAGE138
J 0
(35 5200);
DISPLAY 0.638298 (35 5200);
PAINT PINK (35 5200);
DISPLAY INVISIBLE (35 5200);
FORCEADD DNS..1
(2100 5375);
PAINT RED (2100 5375);
FORCEPROP 2 LAST CDS_LIB mstr_misc
J 0
(2100 5375);
DISPLAY INVISIBLE (2100 5375);
FORCEPROP 1 LAST COMMENT_BODY TRUE
R 1
J 0
(2175 5150);
DISPLAY 0.872340 (2175 5150);
PAINT GREEN (2175 5150);
DISPLAY INVISIBLE (2175 5150);
FORCEADD DNS..1
(2150 3250);
PAINT RED (2150 3250);
FORCEPROP 2 LAST CDS_LIB mstr_misc
J 0
(2150 3250);
DISPLAY INVISIBLE (2150 3250);
FORCEPROP 1 LAST COMMENT_BODY TRUE
R 1
J 0
(2225 3025);
DISPLAY 0.872340 (2225 3025);
PAINT GREEN (2225 3025);
DISPLAY INVISIBLE (2225 3025);
WIRE 16 -1 (1075 4650)(1075 4600);
WIRE 16 -1 (550 4650)(550 4600);
WIRE 16 -1 (2475 2050)(2500 2050);
WIRE 16 -1 (2500 2050)(2500 1900);
WIRE 16 -1 (1075 2525)(1075 2475);
WIRE 16 -1 (550 2525)(550 2475);
WIRE 16 -1 (3375 3900)(3375 3800);
WIRE 16 -1 (3375 1775)(3375 1675);
WIRE 16 -1 (2475 4175)(2500 4175);
WIRE 16 -1 (2500 4175)(2500 4025);
WIRE 16 -1 (3425 4425)(3050 4425);
WIRE 16 -1 (3050 5325)(3050 4425);
WIRE 16 -1 (3050 4425)(2475 4425);
FORCEPROP 2 LAST SIG_NAME SMB_APML_CPU0_R_SDA
J 2
(2990 4435);
DISPLAY 0.489362 (2990 4435);
FORCEPROP 2 LASTPROP $XRERR UNIQUE?
J 0
(2750 4435);
DISPLAY 0.638298 (2750 4435);
PAINT MONO (2750 4435);
DISPLAY INVISIBLE (2750 4435);
WIRE 16 -1 (2125 5325)(3050 5325);
WIRE 16 -1 (4350 4375)(3625 4375);
FORCEPROP 2 LAST SIG_NAME SMB_APML_CPU0_SCL
J 2
(4175 4385);
DISPLAY 0.489362 (4175 4385);
WIRE 16 -1 (3625 4225)(4350 4225);
FORCEPROP 2 LAST SIG_NAME SMB_CPU0_SEC_SDA
J 2
(4175 4235);
DISPLAY 0.489362 (4175 4235);
WIRE 16 -1 (5425 2825)(6600 2825);
FORCEPROP 2 LAST SIG_NAME SMB_APML_CPU1_SCL
J 2
(5965 2835);
DISPLAY 0.489362 (5965 2835);
WIRE 16 -1 (6600 3025)(6600 2825);
WIRE 16 -1 (5425 2775)(6900 2775);
FORCEPROP 2 LAST SIG_NAME SMB_CPU1_SEC_SCL
J 2
(5965 2785);
DISPLAY 0.489362 (5965 2785);
WIRE 16 -1 (6900 3025)(6900 2775);
WIRE 16 -1 (5425 2725)(7225 2725);
FORCEPROP 2 LAST SIG_NAME SMB_CPU1_SEC_SDA
J 2
(5965 2735);
DISPLAY 0.489362 (5965 2735);
WIRE 16 -1 (7225 3025)(7225 2725);
WIRE 16 -1 (6625 3950)(6625 3775);
WIRE 16 -1 (5550 3775)(6625 3775);
FORCEPROP 2 LAST SIG_NAME SMB_APML_CPU0_SCL
J 2
(6065 3785);
DISPLAY 0.489362 (6065 3785);
WIRE 16 -1 (6925 3725)(6925 3950);
WIRE 16 -1 (5550 3725)(6925 3725);
FORCEPROP 2 LAST SIG_NAME SMB_CPU0_SEC_SCL
J 2
(6065 3735);
DISPLAY 0.489362 (6065 3735);
WIRE 16 -1 (7250 3950)(7250 3675);
WIRE 16 -1 (5550 3675)(7250 3675);
FORCEPROP 2 LAST SIG_NAME SMB_CPU0_SEC_SDA
J 2
(6065 3685);
DISPLAY 0.489362 (6065 3685);
WIRE 16 -1 (7225 3425)(7225 3325);
WIRE 16 -1 (7225 3325)(7225 3225);
WIRE 16 -1 (6900 3325)(7225 3325);
WIRE 16 -1 (6900 3325)(6900 3225);
WIRE 16 -1 (6600 3325)(6900 3325);
WIRE 16 -1 (6600 3325)(6600 3225);
WIRE 16 -1 (6275 3325)(6600 3325);
WIRE 16 -1 (6275 3325)(6275 3225);
WIRE 16 -1 (2475 2300)(3050 2300);
FORCEPROP 2 LAST SIG_NAME SMB_APML_CPU1_R_SDA
J 2
(3015 2310);
DISPLAY 0.489362 (3015 2310);
FORCEPROP 2 LASTPROP $XRERR UNIQUE?
J 0
(2775 2310);
DISPLAY 0.638298 (2775 2310);
PAINT MONO (2775 2310);
DISPLAY INVISIBLE (2775 2310);
WIRE 16 -1 (3050 2300)(3450 2300);
WIRE 16 -1 (3050 3200)(3050 2300);
WIRE 16 -1 (2125 3200)(3050 3200);
WIRE 16 -1 (1125 2150)(1125 1425);
WIRE 16 -1 (1125 2150)(1625 2150);
WIRE 16 -1 (300 2150)(1125 2150);
WIRE 16 -1 (1125 1425)(2000 1425);
WIRE 16 -1 (-425 2150)(300 2150);
FORCEPROP 2 LAST SIG_NAME SMB_SCM_11_XLTR_SDA
J 0
(-350 2160);
DISPLAY 0.489362 (-350 2160);
WIRE 16 -1 (300 2150)(300 3200);
WIRE 16 -1 (300 3200)(1925 3200);
WIRE 16 -1 (1925 3275)(225 3275);
WIRE 16 -1 (225 3275)(225 2100);
WIRE 16 -1 (-425 2100)(225 2100);
FORCEPROP 2 LAST SIG_NAME SMB_SCM_11_XLTR_SCL
J 0
(-350 2110);
DISPLAY 0.489362 (-350 2110);
WIRE 16 -1 (225 2100)(1175 2100);
WIRE 16 -1 (1175 2100)(1175 1500);
WIRE 16 -1 (1175 2100)(1625 2100);
WIRE 16 -1 (1175 1500)(2000 1500);
WIRE 16 -1 (1925 5400)(225 5400);
WIRE 16 -1 (225 5400)(225 4225);
WIRE 16 -1 (-400 4225)(225 4225);
FORCEPROP 2 LAST SIG_NAME SMB_SCM_10_XLTR_SCL
J 0
(-350 4235);
DISPLAY 0.489362 (-350 4235);
WIRE 16 -1 (225 4225)(1150 4225);
WIRE 16 -1 (1150 4225)(1150 3625);
WIRE 16 -1 (1150 4225)(1625 4225);
WIRE 16 -1 (1150 3625)(1975 3625);
WIRE 16 -1 (3375 4225)(3425 4225);
WIRE 16 -1 (3375 4225)(3375 4100);
WIRE 16 -1 (3100 4225)(3375 4225);
WIRE 16 -1 (2475 4225)(3100 4225);
FORCEPROP 2 LAST SIG_NAME SMB_CPU0_SEC_R_SDA
J 2
(2990 4235);
DISPLAY 0.489362 (2990 4235);
FORCEPROP 2 LASTPROP $XRERR UNIQUE?
J 0
(2750 4235);
DISPLAY 0.638298 (2750 4235);
PAINT MONO (2750 4235);
DISPLAY INVISIBLE (2750 4235);
WIRE 16 -1 (3100 4225)(3100 3550);
WIRE 16 -1 (2175 3550)(3100 3550);
WIRE 16 -1 (2475 4275)(3025 4275);
FORCEPROP 2 LAST SIG_NAME SMB_CPU0_SEC_R_SCL
J 2
(2990 4285);
DISPLAY 0.489362 (2990 4285);
FORCEPROP 2 LASTPROP $XRERR UNIQUE?
J 0
(2750 4285);
DISPLAY 0.638298 (2750 4285);
PAINT MONO (2750 4285);
DISPLAY INVISIBLE (2750 4285);
WIRE 16 -1 (3025 4275)(3425 4275);
WIRE 16 -1 (3025 4275)(3025 3625);
WIRE 16 -1 (2175 3625)(3025 3625);
WIRE 16 -1 (550 2725)(550 2800);
WIRE 16 -1 (550 2800)(625 2800);
WIRE 16 -1 (625 2800)(700 2800);
WIRE 16 -1 (625 2800)(625 2350);
WIRE 16 -1 (1625 2350)(625 2350);
FORCEPROP 2 LAST SIG_NAME I3C_MUX_CPU1_VIO
J 0
(665 2360);
DISPLAY 0.489362 (665 2360);
FORCEPROP 2 LASTPROP $XRERR UNIQUE?
J 0
(425 2360);
DISPLAY 0.638298 (425 2360);
PAINT MONO (425 2360);
DISPLAY INVISIBLE (425 2360);
WIRE 16 -1 (1625 4525)(1250 4525);
WIRE 16 -1 (1250 4925)(1250 4525);
WIRE 16 -1 (1250 5050)(1250 4925);
WIRE 16 -1 (1075 4925)(1250 4925);
WIRE 16 -1 (1075 4850)(1075 4925);
WIRE 16 -1 (900 4925)(1075 4925);
WIRE 16 -1 (1625 2400)(1250 2400);
WIRE 16 -1 (1250 2800)(1250 2400);
WIRE 16 -1 (1250 2925)(1250 2800);
WIRE 16 -1 (1075 2800)(1250 2800);
WIRE 16 -1 (1075 2725)(1075 2800);
WIRE 16 -1 (900 2800)(1075 2800);
WIRE 16 -1 (6300 4250)(6625 4250);
WIRE 16 -1 (6300 4250)(6300 4150);
WIRE 16 -1 (6925 4250)(6625 4250);
WIRE 16 -1 (6625 4250)(6625 4150);
WIRE 16 -1 (6925 4250)(7250 4250);
WIRE 16 -1 (6925 4250)(6925 4150);
WIRE 16 -1 (7250 4350)(7250 4250);
WIRE 16 -1 (7250 4250)(7250 4150);
WIRE 16 -1 (6275 3025)(6275 2875);
WIRE 16 -1 (5425 2875)(6275 2875);
FORCEPROP 2 LAST SIG_NAME SMB_APML_CPU1_SDA
J 2
(5965 2885);
DISPLAY 0.489362 (5965 2885);
WIRE 16 -1 (1100 4275)(1100 3550);
WIRE 16 -1 (1100 4275)(1625 4275);
WIRE 16 -1 (300 4275)(1100 4275);
WIRE 16 -1 (1100 3550)(1975 3550);
WIRE 16 -1 (-400 4275)(300 4275);
FORCEPROP 2 LAST SIG_NAME SMB_SCM_10_XLTR_SDA
J 0
(-350 4285);
DISPLAY 0.489362 (-350 4285);
WIRE 16 -1 (300 4275)(300 5325);
WIRE 16 -1 (300 5325)(1925 5325);
WIRE 16 -1 (550 4850)(550 4925);
WIRE 16 -1 (550 4925)(625 4925);
WIRE 16 -1 (625 4925)(700 4925);
WIRE 16 -1 (625 4925)(625 4475);
WIRE 16 -1 (1625 4475)(625 4475);
FORCEPROP 2 LAST SIG_NAME I3C_MUX_CPU0_VIO
J 0
(665 4485);
DISPLAY 0.489362 (665 4485);
FORCEPROP 2 LASTPROP $XRERR UNIQUE?
J 0
(425 4485);
DISPLAY 0.638298 (425 4485);
PAINT MONO (425 4485);
DISPLAY INVISIBLE (425 4485);
WIRE 16 -1 (2125 5400)(3100 5400);
WIRE 16 -1 (3100 4375)(3100 5400);
WIRE 16 -1 (3425 4375)(3100 4375);
WIRE 16 -1 (3100 4375)(2475 4375);
FORCEPROP 2 LAST SIG_NAME SMB_APML_CPU0_R_SCL
J 2
(2990 4385);
DISPLAY 0.489362 (2990 4385);
FORCEPROP 2 LASTPROP $XRERR UNIQUE?
J 0
(2750 4385);
DISPLAY 0.638298 (2750 4385);
PAINT MONO (2750 4385);
DISPLAY INVISIBLE (2750 4385);
WIRE 16 -1 (2200 1500)(3050 1500);
WIRE 16 -1 (3050 2150)(3050 1500);
WIRE 16 -1 (3050 2150)(3450 2150);
WIRE 16 -1 (2475 2150)(3050 2150);
FORCEPROP 2 LAST SIG_NAME SMB_CPU1_SEC_R_SCL
J 2
(3015 2160);
DISPLAY 0.489362 (3015 2160);
FORCEPROP 2 LASTPROP $XRERR UNIQUE?
J 0
(2775 2160);
DISPLAY 0.638298 (2775 2160);
PAINT MONO (2775 2160);
DISPLAY INVISIBLE (2775 2160);
WIRE 16 -1 (3375 2100)(3450 2100);
WIRE 16 -1 (3125 2100)(3375 2100);
WIRE 16 -1 (3375 2100)(3375 1975);
WIRE 16 -1 (2475 2100)(3125 2100);
FORCEPROP 2 LAST SIG_NAME SMB_CPU1_SEC_R_SDA
J 2
(3015 2110);
DISPLAY 0.489362 (3015 2110);
FORCEPROP 2 LASTPROP $XRERR UNIQUE?
J 0
(2775 2110);
DISPLAY 0.638298 (2775 2110);
PAINT MONO (2775 2110);
DISPLAY INVISIBLE (2775 2110);
WIRE 16 -1 (3125 2100)(3125 1425);
WIRE 16 -1 (2200 1425)(3125 1425);
WIRE 16 -1 (3650 2250)(4375 2250);
FORCEPROP 2 LAST SIG_NAME SMB_APML_CPU1_SCL
J 2
(4200 2260);
DISPLAY 0.489362 (4200 2260);
WIRE 16 -1 (2125 3275)(3100 3275);
WIRE 16 -1 (3100 2250)(3100 3275);
WIRE 16 -1 (3100 2250)(3450 2250);
WIRE 16 -1 (2475 2250)(3100 2250);
FORCEPROP 2 LAST SIG_NAME SMB_APML_CPU1_R_SCL
J 2
(3015 2260);
DISPLAY 0.489362 (3015 2260);
FORCEPROP 2 LASTPROP $XRERR UNIQUE?
J 0
(2775 2260);
DISPLAY 0.638298 (2775 2260);
PAINT MONO (2775 2260);
DISPLAY INVISIBLE (2775 2260);
WIRE 16 -1 (3650 2300)(4375 2300);
FORCEPROP 2 LAST SIG_NAME SMB_APML_CPU1_SDA
J 2
(4200 2310);
DISPLAY 0.489362 (4200 2310);
WIRE 16 -1 (4350 4425)(3625 4425);
FORCEPROP 2 LAST SIG_NAME SMB_APML_CPU0_SDA
J 2
(4175 4435);
DISPLAY 0.489362 (4175 4435);
WIRE 16 -1 (3650 2100)(4375 2100);
FORCEPROP 2 LAST SIG_NAME SMB_CPU1_SEC_SDA
J 2
(4200 2110);
DISPLAY 0.489362 (4200 2110);
WIRE 16 -1 (3650 2150)(4375 2150);
FORCEPROP 2 LAST SIG_NAME SMB_CPU1_SEC_SCL
J 2
(4200 2160);
DISPLAY 0.489362 (4200 2160);
WIRE 16 -1 (3625 4275)(4350 4275);
FORCEPROP 2 LAST SIG_NAME SMB_CPU0_SEC_SCL
J 2
(4175 4285);
DISPLAY 0.489362 (4175 4285);
WIRE 16 -1 (6300 3950)(6300 3825);
WIRE 16 -1 (5550 3825)(6300 3825);
FORCEPROP 2 LAST SIG_NAME SMB_APML_CPU0_SDA
J 2
(6065 3835);
DISPLAY 0.489362 (6065 3835);
DOT 1 (6900 3325);
DOT 1 (7250 4250);
DOT 1 (6625 4250);
DOT 1 (3100 4375);
DOT 1 (3050 4425);
DOT 1 (3025 4275);
DOT 1 (3050 2300);
DOT 1 (1075 4925);
DOT 1 (1150 4225);
DOT 1 (1100 4275);
DOT 1 (625 4925);
DOT 1 (300 4275);
DOT 1 (225 4225);
DOT 1 (1250 2800);
DOT 1 (1125 2150);
DOT 1 (625 2800);
DOT 1 (300 2150);
DOT 1 (225 2100);
DOT 1 (1250 4925);
DOT 1 (1075 2800);
DOT 1 (6600 3325);
DOT 1 (6925 4250);
DOT 1 (7225 3325);
DOT 1 (3100 4225);
DOT 1 (3375 4225);
DOT 1 (3125 2100);
DOT 1 (3375 2100);
DOT 1 (3050 2150);
DOT 1 (3100 2250);
DOT 1 (1175 2100);
FORCENOTE
ADDR: 0X70/0XE0
(1725 1700) 0;
DISPLAY LEFT (1725 1700);
DISPLAY 1.021277 (1725 1700);
FORCENOTE
ADDR: 0X70/0XE0
(1750 3875) 0;
DISPLAY LEFT (1750 3875);
DISPLAY 1.021277 (1750 3875);
QUIT
